FILE_TYPE = MACRO_DRAWING;
SET COLOR_WIRE YELLOW;
SET COLOR_PROP ORANGE;
SET COLOR_DOT WHITE;
SET COLOR_ARC YELLOW;
SET COLOR_BODY GREEN;
SET COLOR_NOTE PURPLE;
SET PROP_DISPLAY VALUE;
SET PAGE_NUMBER P251;
FORCEADD Q_RES..2
(-6575 2200);
FORCEPROP 1 LAST LOCATION R3704
J 0
(-6530 2325);
DISPLAY 0.978723 (-6530 2325);
FORCEPROP 2 LAST $SEC 1
J 0
(-6525 2425);
DISPLAY 0.680851 (-6525 2425);
PAINT MONO (-6525 2425);
DISPLAY INVISIBLE (-6525 2425);
FORCEPROP 2 LAST CDS_SEC 1
J 0
(-6525 2425);
DISPLAY 1.021277 (-6525 2425);
DISPLAY INVISIBLE (-6525 2425);
FORCEPROP 1 LASTPIN (-6575 2300) $PN 1
J 0
(-6570 2262);
DISPLAY 0.787234 (-6570 2262);
FORCEPROP 1 LASTPIN (-6575 2100) $PN 2
J 0
(-6570 2110);
DISPLAY 0.787234 (-6570 2110);
FORCEPROP 1 LAST TOLERANCE 1%
J 0
(-6530 2225);
DISPLAY 0.638298 (-6530 2225);
FORCEPROP 1 LAST MATERIAL CHIP
J 0
(-6535 2125);
DISPLAY 0.638298 (-6535 2125);
FORCEPROP 1 LAST PACK_TYPE 0402LF
J 0
(-6535 2075);
DISPLAY 0.638298 (-6535 2075);
FORCEPROP 1 LAST VALUE 1K
J 0
(-6530 2275);
DISPLAY 0.638298 (-6530 2275);
FORCEPROP 1 LAST WATTAGE 1/16W
J 0
(-6535 2175);
DISPLAY 0.638298 (-6535 2175);
FORCEPROP 2 LAST CDS_LIB pure_quanta
J 0
(-6575 2200);
PAINT MONO (-6575 2200);
DISPLAY INVISIBLE (-6575 2200);
FORCEPROP 1 LAST PATH I1
J 0
(-6525 2375);
DISPLAY 0.978723 (-6525 2375);
PAINT WHITE (-6525 2375);
DISPLAY INVISIBLE (-6525 2375);
FORCEPROP 1 LAST PART_NUMBER CS21002FB06
J 0
(-6535 2075);
DISPLAY 0.510638 (-6535 2075);
DISPLAY INVISIBLE (-6535 2075);
FORCEADD Q_RES..2
(-6025 2850);
FORCEPROP 1 LAST LOCATION R3708
J 0
(-5980 2975);
DISPLAY 0.978723 (-5980 2975);
FORCEPROP 2 LAST $SEC 1
J 0
(-5975 3075);
DISPLAY 0.680851 (-5975 3075);
PAINT MONO (-5975 3075);
DISPLAY INVISIBLE (-5975 3075);
FORCEPROP 2 LAST CDS_SEC 1
J 0
(-5975 3075);
DISPLAY 1.021277 (-5975 3075);
DISPLAY INVISIBLE (-5975 3075);
FORCEPROP 1 LASTPIN (-6025 2950) $PN 1
J 0
(-6020 2912);
DISPLAY 0.787234 (-6020 2912);
FORCEPROP 1 LASTPIN (-6025 2750) $PN 2
J 0
(-6020 2760);
DISPLAY 0.787234 (-6020 2760);
FORCEPROP 1 LAST WATTAGE 1/16W
J 0
(-5985 2825);
DISPLAY 0.638298 (-5985 2825);
FORCEPROP 1 LAST VALUE 10K
J 0
(-5980 2925);
DISPLAY 0.638298 (-5980 2925);
FORCEPROP 1 LAST TOLERANCE 1%
J 0
(-5980 2875);
DISPLAY 0.638298 (-5980 2875);
FORCEPROP 1 LAST MATERIAL EMPTY
J 0
(-5985 2775);
DISPLAY 0.638298 (-5985 2775);
PAINT RED (-5985 2775);
FORCEPROP 1 LAST PACK_TYPE 0402LF
J 0
(-5985 2675);
DISPLAY 0.638298 (-5985 2675);
FORCEPROP 2 LAST CDS_LIB pure_quanta
J 0
(-6025 2850);
PAINT MONO (-6025 2850);
DISPLAY INVISIBLE (-6025 2850);
FORCEPROP 1 LAST PATH I10
J 0
(-5975 3025);
DISPLAY 0.978723 (-5975 3025);
PAINT WHITE (-5975 3025);
DISPLAY INVISIBLE (-5975 3025);
FORCEPROP 1 LAST PART_NUMBER CS31002FB08
J 0
(-5985 2725);
DISPLAY 0.510638 (-5985 2725);
DISPLAY INVISIBLE (-5985 2725);
FORCEADD OFFPAGE..5
(-6800 3950);
FORCEPROP 2 LAST $XR1 253 
J 0
(-7205 3950);
DISPLAY 0.638298 (-7205 3950);
PAINT MONO (-7205 3950);
FORCEPROP 2 LAST $XR0 236 
J 0
(-7085 3950);
DISPLAY 0.638298 (-7085 3950);
PAINT MONO (-7085 3950);
FORCEPROP 2 LAST CDS_LIB standard
J 2
(-6800 3950);
DISPLAY INVISIBLE (-6800 3950);
FORCEPROP 1 LAST OFFPAGE TRUE
J 0
(-6475 3825);
DISPLAY 0.872340 (-6475 3825);
DISPLAY INVISIBLE (-6475 3825);
FORCEPROP 1 LAST COMMENT_BODY TRUE
J 0
(-6700 3875);
DISPLAY 0.872340 (-6700 3875);
PAINT GREEN (-6700 3875);
DISPLAY INVISIBLE (-6700 3875);
FORCEPROP 2 LAST PATH I11
J 0
(-7075 4000);
DISPLAY 0.680851 (-7075 4000);
DISPLAY INVISIBLE (-7075 4000);
FORCEADD OFFPAGE..3
R 2
(-6800 4000);
FORCEPROP 2 LAST $XR1 236 
J 0
(-7230 4000);
DISPLAY 0.638298 (-7230 4000);
PAINT MONO (-7230 4000);
FORCEPROP 2 LAST $XR0 253 
J 0
(-7110 4000);
DISPLAY 0.638298 (-7110 4000);
PAINT MONO (-7110 4000);
FORCEPROP 2 LAST CDS_LIB standard
J 2
(-6800 4000);
DISPLAY INVISIBLE (-6800 4000);
FORCEPROP 1 LAST OFFPAGE TRUE
J 2
(-7125 3875);
DISPLAY 0.872340 (-7125 3875);
DISPLAY INVISIBLE (-7125 3875);
FORCEPROP 1 LAST COMMENT_BODY TRUE
J 2
(-6750 3900);
DISPLAY 0.872340 (-6750 3900);
PAINT GREEN (-6750 3900);
DISPLAY INVISIBLE (-6750 3900);
FORCEPROP 2 LAST PATH I12
J 0
(-7100 4050);
DISPLAY 0.680851 (-7100 4050);
DISPLAY INVISIBLE (-7100 4050);
FORCEADD OFFPAGE..5
(-6800 4050);
FORCEPROP 2 LAST $XR1 253 
J 0
(-7205 4050);
DISPLAY 0.638298 (-7205 4050);
PAINT MONO (-7205 4050);
FORCEPROP 2 LAST $XR0 236 
J 0
(-7085 4050);
DISPLAY 0.638298 (-7085 4050);
PAINT MONO (-7085 4050);
FORCEPROP 2 LAST CDS_LIB standard
J 2
(-6800 4050);
DISPLAY INVISIBLE (-6800 4050);
FORCEPROP 1 LAST OFFPAGE TRUE
J 0
(-6475 3925);
DISPLAY 0.872340 (-6475 3925);
DISPLAY INVISIBLE (-6475 3925);
FORCEPROP 1 LAST COMMENT_BODY TRUE
J 0
(-6700 3975);
DISPLAY 0.872340 (-6700 3975);
PAINT GREEN (-6700 3975);
DISPLAY INVISIBLE (-6700 3975);
FORCEPROP 2 LAST PATH I13
J 0
(-7075 4100);
DISPLAY 0.680851 (-7075 4100);
DISPLAY INVISIBLE (-7075 4100);
FORCEADD OFFPAGE..3
R 2
(-6800 4100);
FORCEPROP 2 LAST $XR1 236 
J 0
(-7230 4100);
DISPLAY 0.638298 (-7230 4100);
PAINT MONO (-7230 4100);
FORCEPROP 2 LAST $XR0 253 
J 0
(-7110 4100);
DISPLAY 0.638298 (-7110 4100);
PAINT MONO (-7110 4100);
FORCEPROP 2 LAST CDS_LIB standard
J 2
(-6800 4100);
DISPLAY INVISIBLE (-6800 4100);
FORCEPROP 1 LAST OFFPAGE TRUE
J 2
(-7125 3975);
DISPLAY 0.872340 (-7125 3975);
DISPLAY INVISIBLE (-7125 3975);
FORCEPROP 1 LAST COMMENT_BODY TRUE
J 2
(-6750 4000);
DISPLAY 0.872340 (-6750 4000);
PAINT GREEN (-6750 4000);
DISPLAY INVISIBLE (-6750 4000);
FORCEPROP 2 LAST PATH I14
J 0
(-7100 4150);
DISPLAY 0.680851 (-7100 4150);
DISPLAY INVISIBLE (-7100 4150);
FORCEADD OFFPAGE..2
(-4900 2425);
FORCEPROP 2 LAST $XR0 253 
J 0
(-4711 2425);
DISPLAY 0.638298 (-4711 2425);
PAINT MONO (-4711 2425);
FORCEPROP 2 LAST CDS_LIB standard
J 0
(-4900 2425);
PAINT MONO (-4900 2425);
DISPLAY INVISIBLE (-4900 2425);
FORCEPROP 1 LAST OFFPAGE TRUE
J 0
(-4575 2300);
DISPLAY 0.872340 (-4575 2300);
DISPLAY INVISIBLE (-4575 2300);
FORCEPROP 1 LAST COMMENT_BODY TRUE
J 0
(-4945 2330);
DISPLAY 0.872340 (-4945 2330);
PAINT GREEN (-4945 2330);
DISPLAY INVISIBLE (-4945 2330);
FORCEPROP 2 LAST PATH I15
J 0
(-4700 2475);
DISPLAY 0.680851 (-4700 2475);
DISPLAY INVISIBLE (-4700 2475);
FORCEADD OFFPAGE..2
(-4900 2500);
FORCEPROP 2 LAST $XR0 253 
J 0
(-4711 2500);
DISPLAY 0.638298 (-4711 2500);
PAINT MONO (-4711 2500);
FORCEPROP 2 LAST CDS_LIB standard
J 0
(-4900 2500);
PAINT MONO (-4900 2500);
DISPLAY INVISIBLE (-4900 2500);
FORCEPROP 1 LAST OFFPAGE TRUE
J 0
(-4575 2375);
DISPLAY 0.872340 (-4575 2375);
DISPLAY INVISIBLE (-4575 2375);
FORCEPROP 1 LAST COMMENT_BODY TRUE
J 0
(-4945 2405);
DISPLAY 0.872340 (-4945 2405);
PAINT GREEN (-4945 2405);
DISPLAY INVISIBLE (-4945 2405);
FORCEPROP 2 LAST PATH I16
J 0
(-4700 2550);
DISPLAY 0.680851 (-4700 2550);
DISPLAY INVISIBLE (-4700 2550);
FORCEADD OFFPAGE..2
(-4900 2575);
FORCEPROP 2 LAST $XR0 253 
J 0
(-4711 2575);
DISPLAY 0.638298 (-4711 2575);
PAINT MONO (-4711 2575);
FORCEPROP 2 LAST CDS_LIB standard
J 0
(-4900 2575);
PAINT MONO (-4900 2575);
DISPLAY INVISIBLE (-4900 2575);
FORCEPROP 1 LAST OFFPAGE TRUE
J 0
(-4575 2450);
DISPLAY 0.872340 (-4575 2450);
DISPLAY INVISIBLE (-4575 2450);
FORCEPROP 1 LAST COMMENT_BODY TRUE
J 0
(-4945 2480);
DISPLAY 0.872340 (-4945 2480);
PAINT GREEN (-4945 2480);
DISPLAY INVISIBLE (-4945 2480);
FORCEPROP 2 LAST PATH I17
J 0
(-4700 2625);
DISPLAY 0.680851 (-4700 2625);
DISPLAY INVISIBLE (-4700 2625);
FORCEADD Q_RES..1
R 2
(-5600 3950);
FORCEPROP 1 LAST LOCATION R3719
J 2
(-5375 3950);
DISPLAY 0.510638 (-5375 3950);
FORCEPROP 0 LAST $SEC 1
J 2
(-5375 4000);
DISPLAY INVISIBLE (-5375 4000);
FORCEPROP 0 LAST CDS_SEC 1
J 2
(-5375 4000);
DISPLAY INVISIBLE (-5375 4000);
FORCEPROP 1 LASTPIN (-5500 3950) $PN 1
J 2
(-5512 3962);
DISPLAY 0.787234 (-5512 3962);
PAINT MONO (-5512 3962);
DISPLAY INVISIBLE (-5512 3962);
FORCEPROP 1 LASTPIN (-5700 3950) $PN 2
J 2
(-5662 3962);
DISPLAY 0.787234 (-5662 3962);
PAINT MONO (-5662 3962);
DISPLAY INVISIBLE (-5662 3962);
FORCEPROP 1 LAST VALUE 0
J 0
(-5750 3950);
DISPLAY 0.510638 (-5750 3950);
FORCEPROP 1 LAST MATERIAL CHIP
J 2
(-5850 3950);
DISPLAY 0.510638 (-5850 3950);
FORCEPROP 1 LAST TOLERANCE 5%
J 2
(-5775 3950);
DISPLAY 0.510638 (-5775 3950);
FORCEPROP 1 LAST PACK_TYPE 0402LF
J 2
(-5850 3950);
DISPLAY 0.510638 (-5850 3950);
DISPLAY INVISIBLE (-5850 3950);
FORCEPROP 1 LAST WATTAGE 1/16W
J 0
(-5700 3875);
DISPLAY 0.319149 (-5700 3875);
DISPLAY INVISIBLE (-5700 3875);
FORCEPROP 2 LAST CDS_LIB pure_quanta
J 2
(-5600 3950);
DISPLAY INVISIBLE (-5600 3950);
FORCEPROP 1 LAST PATH I18
J 2
(-5550 4100);
DISPLAY 0.978723 (-5550 4100);
PAINT WHITE (-5550 4100);
DISPLAY INVISIBLE (-5550 4100);
FORCEPROP 1 LAST PART_NUMBER CS00002JB13
J 2
(-5525 3900);
DISPLAY 0.319149 (-5525 3900);
DISPLAY INVISIBLE (-5525 3900);
FORCEADD Q_RES..1
R 2
(-5600 4000);
FORCEPROP 1 LAST LOCATION R3720
J 2
(-5375 4000);
DISPLAY 0.510638 (-5375 4000);
FORCEPROP 0 LAST $SEC 1
J 2
(-5375 4050);
DISPLAY INVISIBLE (-5375 4050);
FORCEPROP 0 LAST CDS_SEC 1
J 2
(-5375 4050);
DISPLAY INVISIBLE (-5375 4050);
FORCEPROP 1 LASTPIN (-5500 4000) $PN 1
J 2
(-5512 4012);
DISPLAY 0.787234 (-5512 4012);
PAINT MONO (-5512 4012);
DISPLAY INVISIBLE (-5512 4012);
FORCEPROP 1 LASTPIN (-5700 4000) $PN 2
J 2
(-5662 4012);
DISPLAY 0.787234 (-5662 4012);
PAINT MONO (-5662 4012);
DISPLAY INVISIBLE (-5662 4012);
FORCEPROP 1 LAST VALUE 0
J 0
(-5750 4000);
DISPLAY 0.510638 (-5750 4000);
FORCEPROP 1 LAST TOLERANCE 5%
J 2
(-5775 4000);
DISPLAY 0.510638 (-5775 4000);
FORCEPROP 1 LAST MATERIAL CHIP
J 2
(-5850 4000);
DISPLAY 0.510638 (-5850 4000);
FORCEPROP 2 LAST CDS_LIB pure_quanta
J 2
(-5600 4000);
DISPLAY INVISIBLE (-5600 4000);
FORCEPROP 1 LAST PACK_TYPE 0402LF
J 2
(-5500 3900);
DISPLAY 0.510638 (-5500 3900);
DISPLAY INVISIBLE (-5500 3900);
FORCEPROP 1 LAST WATTAGE 1/16W
J 0
(-5775 3900);
DISPLAY 0.510638 (-5775 3900);
DISPLAY INVISIBLE (-5775 3900);
FORCEPROP 1 LAST PATH I19
J 2
(-5550 4150);
DISPLAY 0.978723 (-5550 4150);
PAINT WHITE (-5550 4150);
DISPLAY INVISIBLE (-5550 4150);
FORCEPROP 1 LAST PART_NUMBER CS00002JB13
J 2
(-5500 3950);
DISPLAY 0.510638 (-5500 3950);
DISPLAY INVISIBLE (-5500 3950);
FORCEADD UNIVERSAL_GND..1
(-6575 1975);
FORCEPROP 3 LASTPIN (-6575 2025) SIG_NAME GND\g
J 0
(-6565 2035);
DISPLAY 0.659574 (-6565 2035);
PAINT MONO (-6565 2035);
DISPLAY INVISIBLE (-6565 2035);
FORCEPROP 2 LAST ROOM IO_SLOT
J 1
(-6800 2050);
DISPLAY 0.744681 (-6800 2050);
FORCEPROP 2 LAST CDS_LIB pure_quanta_power
J 0
(-6575 1975);
PAINT MONO (-6575 1975);
DISPLAY INVISIBLE (-6575 1975);
FORCEPROP 1 LAST HDL_POWER GND
J 1
(-6550 1900);
DISPLAY 0.872340 (-6550 1900);
PAINT GREEN (-6550 1900);
DISPLAY INVISIBLE (-6550 1900);
FORCEPROP 1 LAST PATH I2
J 0
(-6500 1975);
DISPLAY 0.872340 (-6500 1975);
PAINT AQUA (-6500 1975);
DISPLAY INVISIBLE (-6500 1975);
FORCEADD Q_RES..1
R 2
(-5600 4050);
FORCEPROP 1 LAST LOCATION R3717
J 2
(-5375 4050);
DISPLAY 0.510638 (-5375 4050);
FORCEPROP 0 LAST $SEC 1
J 2
(-5375 4100);
DISPLAY INVISIBLE (-5375 4100);
FORCEPROP 0 LAST CDS_SEC 1
J 2
(-5375 4100);
DISPLAY INVISIBLE (-5375 4100);
FORCEPROP 1 LASTPIN (-5500 4050) $PN 1
J 2
(-5512 4062);
DISPLAY 0.787234 (-5512 4062);
PAINT MONO (-5512 4062);
DISPLAY INVISIBLE (-5512 4062);
FORCEPROP 1 LASTPIN (-5700 4050) $PN 2
J 2
(-5662 4062);
DISPLAY 0.787234 (-5662 4062);
PAINT MONO (-5662 4062);
DISPLAY INVISIBLE (-5662 4062);
FORCEPROP 1 LAST VALUE 0
J 0
(-5750 4050);
DISPLAY 0.510638 (-5750 4050);
FORCEPROP 1 LAST TOLERANCE 5%
J 2
(-5775 4050);
DISPLAY 0.510638 (-5775 4050);
FORCEPROP 1 LAST MATERIAL CHIP
J 2
(-5850 4050);
DISPLAY 0.510638 (-5850 4050);
FORCEPROP 2 LAST CDS_LIB pure_quanta
J 2
(-5600 4050);
DISPLAY INVISIBLE (-5600 4050);
FORCEPROP 1 LAST WATTAGE 1/16W
J 0
(-5700 3975);
DISPLAY 0.319149 (-5700 3975);
DISPLAY INVISIBLE (-5700 3975);
FORCEPROP 1 LAST PACK_TYPE 0402LF
J 2
(-5850 4050);
DISPLAY 0.510638 (-5850 4050);
DISPLAY INVISIBLE (-5850 4050);
FORCEPROP 1 LAST PATH I20
J 2
(-5550 4200);
DISPLAY 0.978723 (-5550 4200);
PAINT WHITE (-5550 4200);
DISPLAY INVISIBLE (-5550 4200);
FORCEPROP 1 LAST PART_NUMBER CS00002JB13
J 2
(-5525 4000);
DISPLAY 0.319149 (-5525 4000);
DISPLAY INVISIBLE (-5525 4000);
FORCEADD Q_RES..1
R 2
(-5600 4100);
FORCEPROP 1 LAST LOCATION R3718
J 2
(-5375 4100);
DISPLAY 0.510638 (-5375 4100);
FORCEPROP 0 LAST $SEC 1
J 2
(-5375 4150);
DISPLAY INVISIBLE (-5375 4150);
FORCEPROP 0 LAST CDS_SEC 1
J 2
(-5375 4150);
DISPLAY INVISIBLE (-5375 4150);
FORCEPROP 1 LASTPIN (-5500 4100) $PN 1
J 2
(-5512 4112);
DISPLAY 0.787234 (-5512 4112);
PAINT MONO (-5512 4112);
DISPLAY INVISIBLE (-5512 4112);
FORCEPROP 1 LASTPIN (-5700 4100) $PN 2
J 2
(-5662 4112);
DISPLAY 0.787234 (-5662 4112);
PAINT MONO (-5662 4112);
DISPLAY INVISIBLE (-5662 4112);
FORCEPROP 1 LAST TOLERANCE 5%
J 2
(-5775 4100);
DISPLAY 0.510638 (-5775 4100);
FORCEPROP 1 LAST VALUE 0
J 0
(-5750 4100);
DISPLAY 0.510638 (-5750 4100);
FORCEPROP 1 LAST MATERIAL CHIP
J 2
(-5850 4100);
DISPLAY 0.510638 (-5850 4100);
FORCEPROP 1 LAST WATTAGE 1/16W
J 0
(-5775 4000);
DISPLAY 0.510638 (-5775 4000);
DISPLAY INVISIBLE (-5775 4000);
FORCEPROP 1 LAST PACK_TYPE 0402LF
J 2
(-5500 4000);
DISPLAY 0.510638 (-5500 4000);
DISPLAY INVISIBLE (-5500 4000);
FORCEPROP 2 LAST CDS_LIB pure_quanta
J 2
(-5600 4100);
DISPLAY INVISIBLE (-5600 4100);
FORCEPROP 1 LAST PATH I21
J 2
(-5550 4250);
DISPLAY 0.978723 (-5550 4250);
PAINT WHITE (-5550 4250);
DISPLAY INVISIBLE (-5550 4250);
FORCEPROP 1 LAST PART_NUMBER CS00002JB13
J 2
(-5500 4050);
DISPLAY 0.510638 (-5500 4050);
DISPLAY INVISIBLE (-5500 4050);
FORCEADD OFFPAGE..1
(-7475 4400);
FORCEPROP 2 LAST $XR4 246 
J 0
(-8206 4400);
DISPLAY 0.638298 (-8206 4400);
PAINT MONO (-8206 4400);
FORCEPROP 2 LAST $XR3 241 
J 0
(-8086 4400);
DISPLAY 0.638298 (-8086 4400);
PAINT MONO (-8086 4400);
FORCEPROP 2 LAST $XR2 139 
J 0
(-7966 4400);
DISPLAY 0.638298 (-7966 4400);
PAINT MONO (-7966 4400);
FORCEPROP 2 LAST $XR1 132 
J 0
(-7846 4400);
DISPLAY 0.638298 (-7846 4400);
PAINT MONO (-7846 4400);
FORCEPROP 2 LAST $XR0 80 
J 0
(-7726 4400);
DISPLAY 0.638298 (-7726 4400);
PAINT MONO (-7726 4400);
FORCEPROP 2 LAST $XR5 251 
J 0
(-8326 4400);
DISPLAY 0.638298 (-8326 4400);
PAINT MONO (-8326 4400);
FORCEPROP 2 LAST CDS_LIB standard
J 0
(-7475 4400);
DISPLAY INVISIBLE (-7475 4400);
FORCEPROP 1 LAST OFFPAGE TRUE
J 0
(-7150 4275);
DISPLAY 0.872340 (-7150 4275);
DISPLAY INVISIBLE (-7150 4275);
FORCEPROP 1 LAST COMMENT_BODY TRUE
J 0
(-7350 4300);
DISPLAY 0.872340 (-7350 4300);
PAINT GREEN (-7350 4300);
DISPLAY INVISIBLE (-7350 4300);
FORCEPROP 2 LAST PATH I22
J 0
(-7725 4450);
DISPLAY 0.680851 (-7725 4450);
DISPLAY INVISIBLE (-7725 4450);
FORCEADD OFFPAGE..5
(-6800 4150);
FORCEPROP 2 LAST $XR2 272 
J 0
(-7325 4150);
DISPLAY 0.638298 (-7325 4150);
PAINT MONO (-7325 4150);
FORCEPROP 2 LAST $XR1 253 
J 0
(-7205 4150);
DISPLAY 0.638298 (-7205 4150);
PAINT MONO (-7205 4150);
FORCEPROP 2 LAST $XR0 236 
J 0
(-7085 4150);
DISPLAY 0.638298 (-7085 4150);
PAINT MONO (-7085 4150);
FORCEPROP 2 LAST CDS_LIB standard
J 2
(-6800 4150);
DISPLAY INVISIBLE (-6800 4150);
FORCEPROP 1 LAST OFFPAGE TRUE
J 0
(-6475 4025);
DISPLAY 0.872340 (-6475 4025);
DISPLAY INVISIBLE (-6475 4025);
FORCEPROP 1 LAST COMMENT_BODY TRUE
J 0
(-6700 4075);
DISPLAY 0.872340 (-6700 4075);
PAINT GREEN (-6700 4075);
DISPLAY INVISIBLE (-6700 4075);
FORCEPROP 2 LAST PATH I23
J 0
(-7075 4200);
DISPLAY 0.680851 (-7075 4200);
DISPLAY INVISIBLE (-7075 4200);
FORCEADD OFFPAGE..3
R 2
(-6800 4200);
FORCEPROP 2 LAST $XR2 236 
J 0
(-7350 4200);
DISPLAY 0.638298 (-7350 4200);
PAINT MONO (-7350 4200);
FORCEPROP 2 LAST $XR1 272 
J 0
(-7230 4200);
DISPLAY 0.638298 (-7230 4200);
PAINT MONO (-7230 4200);
FORCEPROP 2 LAST $XR0 253 
J 0
(-7110 4200);
DISPLAY 0.638298 (-7110 4200);
PAINT MONO (-7110 4200);
FORCEPROP 2 LAST CDS_LIB standard
J 2
(-6800 4200);
DISPLAY INVISIBLE (-6800 4200);
FORCEPROP 1 LAST OFFPAGE TRUE
J 2
(-7125 4075);
DISPLAY 0.872340 (-7125 4075);
DISPLAY INVISIBLE (-7125 4075);
FORCEPROP 1 LAST COMMENT_BODY TRUE
J 2
(-6750 4100);
DISPLAY 0.872340 (-6750 4100);
PAINT GREEN (-6750 4100);
DISPLAY INVISIBLE (-6750 4100);
FORCEPROP 2 LAST PATH I24
J 0
(-7100 4250);
DISPLAY 0.680851 (-7100 4250);
DISPLAY INVISIBLE (-7100 4250);
FORCEADD OFFPAGE..5
(-6800 4250);
FORCEPROP 2 LAST $XR1 151 
J 0
(-7205 4250);
DISPLAY 0.638298 (-7205 4250);
PAINT MONO (-7205 4250);
FORCEPROP 2 LAST $XR0 253 
J 0
(-7085 4250);
DISPLAY 0.638298 (-7085 4250);
PAINT MONO (-7085 4250);
FORCEPROP 2 LAST CDS_LIB standard
J 2
(-6800 4250);
DISPLAY INVISIBLE (-6800 4250);
FORCEPROP 1 LAST OFFPAGE TRUE
J 0
(-6475 4125);
DISPLAY 0.872340 (-6475 4125);
DISPLAY INVISIBLE (-6475 4125);
FORCEPROP 1 LAST COMMENT_BODY TRUE
J 0
(-6700 4175);
DISPLAY 0.872340 (-6700 4175);
PAINT GREEN (-6700 4175);
DISPLAY INVISIBLE (-6700 4175);
FORCEPROP 2 LAST PATH I25
J 0
(-7075 4300);
DISPLAY 0.680851 (-7075 4300);
DISPLAY INVISIBLE (-7075 4300);
FORCEADD OFFPAGE..3
R 2
(-6800 4300);
FORCEPROP 2 LAST $XR1 253 
J 0
(-7230 4300);
DISPLAY 0.638298 (-7230 4300);
PAINT MONO (-7230 4300);
FORCEPROP 2 LAST $XR0 151 
J 0
(-7110 4300);
DISPLAY 0.638298 (-7110 4300);
PAINT MONO (-7110 4300);
FORCEPROP 2 LAST CDS_LIB standard
J 2
(-6800 4300);
DISPLAY INVISIBLE (-6800 4300);
FORCEPROP 1 LAST OFFPAGE TRUE
J 2
(-7125 4175);
DISPLAY 0.872340 (-7125 4175);
DISPLAY INVISIBLE (-7125 4175);
FORCEPROP 1 LAST COMMENT_BODY TRUE
J 2
(-6750 4200);
DISPLAY 0.872340 (-6750 4200);
PAINT GREEN (-6750 4200);
DISPLAY INVISIBLE (-6750 4200);
FORCEPROP 2 LAST PATH I26
J 0
(-7100 4350);
DISPLAY 0.680851 (-7100 4350);
DISPLAY INVISIBLE (-7100 4350);
FORCEADD Q_RES..2
R 2
(-6950 4750);
FORCEPROP 1 LAST LOCATION R3705
J 2
(-6995 4875);
DISPLAY 0.978723 (-6995 4875);
FORCEPROP 2 LAST $SEC 1
J 0
(-7000 4975);
DISPLAY 0.680851 (-7000 4975);
PAINT MONO (-7000 4975);
DISPLAY INVISIBLE (-7000 4975);
FORCEPROP 2 LAST CDS_SEC 1
J 0
(-7000 4975);
DISPLAY 1.021277 (-7000 4975);
DISPLAY INVISIBLE (-7000 4975);
FORCEPROP 1 LASTPIN (-6950 4850) $PN 1
J 2
(-6955 4812);
DISPLAY 0.787234 (-6955 4812);
FORCEPROP 1 LASTPIN (-6950 4650) $PN 2
J 2
(-6955 4660);
DISPLAY 0.787234 (-6955 4660);
FORCEPROP 1 LAST WATTAGE 1/16W
J 2
(-6990 4725);
DISPLAY 0.638298 (-6990 4725);
FORCEPROP 1 LAST VALUE 10K
J 2
(-6995 4825);
DISPLAY 0.638298 (-6995 4825);
FORCEPROP 1 LAST PACK_TYPE 0402LF
J 2
(-6990 4625);
DISPLAY 0.638298 (-6990 4625);
FORCEPROP 1 LAST MATERIAL EMPTY
J 2
(-6990 4675);
DISPLAY 0.638298 (-6990 4675);
PAINT RED (-6990 4675);
FORCEPROP 1 LAST TOLERANCE 1%
J 2
(-6995 4775);
DISPLAY 0.638298 (-6995 4775);
FORCEPROP 2 LAST CDS_LIB pure_quanta
J 2
(-6950 4750);
PAINT MONO (-6950 4750);
DISPLAY INVISIBLE (-6950 4750);
FORCEPROP 1 LAST PATH I27
J 2
(-7000 4925);
DISPLAY 0.978723 (-7000 4925);
PAINT WHITE (-7000 4925);
DISPLAY INVISIBLE (-7000 4925);
FORCEPROP 1 LAST PART_NUMBER CS31002FB08
J 2
(-6990 4575);
DISPLAY 0.638298 (-6990 4575);
DISPLAY INVISIBLE (-6990 4575);
FORCEADD UNIVERSAL_POWER..1
(-6950 5025);
FORCEPROP 3 LASTPIN (-6950 4975) SIG_NAME P3V3_AUX\g
J 0
(-6940 4985);
DISPLAY 0.659574 (-6940 4985);
PAINT MONO (-6940 4985);
DISPLAY INVISIBLE (-6940 4985);
FORCEPROP 1 LAST HDL_POWER P3V3_AUX
J 1
(-6950 5075);
DISPLAY 0.872340 (-6950 5075);
PAINT GREEN (-6950 5075);
FORCEPROP 2 LAST CDS_LIB pure_quanta_power
J 0
(-6950 5025);
DISPLAY INVISIBLE (-6950 5025);
FORCEPROP 1 LAST PATH I28
J 0
(-6900 5050);
DISPLAY 0.872340 (-6900 5050);
PAINT AQUA (-6900 5050);
DISPLAY INVISIBLE (-6900 5050);
FORCEADD Q_RES..1
(-5850 4400);
FORCEPROP 1 LAST LOCATION R3710
J 0
(-6075 4400);
DISPLAY 0.638298 (-6075 4400);
FORCEPROP 0 LAST $SEC 1
J 0
(-6075 4450);
DISPLAY 0.680851 (-6075 4450);
PAINT MONO (-6075 4450);
DISPLAY INVISIBLE (-6075 4450);
FORCEPROP 0 LAST CDS_SEC 1
J 0
(-6075 4450);
DISPLAY 1.021277 (-6075 4450);
DISPLAY INVISIBLE (-6075 4450);
FORCEPROP 1 LASTPIN (-5950 4400) $PN 1
J 0
(-5938 4412);
DISPLAY 0.787234 (-5938 4412);
PAINT MONO (-5938 4412);
FORCEPROP 1 LASTPIN (-5750 4400) $PN 2
J 0
(-5788 4412);
DISPLAY 0.787234 (-5788 4412);
PAINT MONO (-5788 4412);
FORCEPROP 1 LAST VALUE 0
J 2
(-5700 4400);
DISPLAY 0.510638 (-5700 4400);
FORCEPROP 1 LAST MATERIAL CHIP
J 0
(-5600 4400);
DISPLAY 0.510638 (-5600 4400);
FORCEPROP 1 LAST TOLERANCE 5%
J 0
(-5675 4400);
DISPLAY 0.510638 (-5675 4400);
FORCEPROP 2 LAST CDS_LIB pure_quanta
J 0
(-5850 4400);
DISPLAY INVISIBLE (-5850 4400);
FORCEPROP 1 LAST WATTAGE 1/16W
J 2
(-5750 4325);
DISPLAY 0.319149 (-5750 4325);
DISPLAY INVISIBLE (-5750 4325);
FORCEPROP 1 LAST PACK_TYPE 0402LF
J 0
(-5600 4400);
DISPLAY 0.510638 (-5600 4400);
DISPLAY INVISIBLE (-5600 4400);
FORCEPROP 1 LAST PATH I29
J 0
(-5900 4550);
DISPLAY 0.978723 (-5900 4550);
PAINT WHITE (-5900 4550);
DISPLAY INVISIBLE (-5900 4550);
FORCEPROP 1 LAST PART_NUMBER CS00002JB13
J 0
(-5925 4350);
DISPLAY 0.319149 (-5925 4350);
DISPLAY INVISIBLE (-5925 4350);
FORCEADD UNIVERSAL_GND..1
(-6300 1975);
FORCEPROP 3 LASTPIN (-6300 2025) SIG_NAME GND\g
J 0
(-6290 2035);
DISPLAY 0.659574 (-6290 2035);
PAINT MONO (-6290 2035);
DISPLAY INVISIBLE (-6290 2035);
FORCEPROP 2 LAST ROOM IO_SLOT
J 1
(-6525 2050);
DISPLAY 0.744681 (-6525 2050);
FORCEPROP 2 LAST CDS_LIB pure_quanta_power
J 0
(-6300 1975);
PAINT MONO (-6300 1975);
DISPLAY INVISIBLE (-6300 1975);
FORCEPROP 1 LAST HDL_POWER GND
J 1
(-6275 1900);
DISPLAY 0.872340 (-6275 1900);
PAINT GREEN (-6275 1900);
DISPLAY INVISIBLE (-6275 1900);
FORCEPROP 1 LAST PATH I3
J 0
(-6225 1975);
DISPLAY 0.872340 (-6225 1975);
PAINT AQUA (-6225 1975);
DISPLAY INVISIBLE (-6225 1975);
FORCEADD Q_RES..1
R 2
(-5600 4200);
FORCEPROP 1 LAST LOCATION R3716
J 2
(-5375 4200);
DISPLAY 0.510638 (-5375 4200);
FORCEPROP 0 LAST $SEC 1
J 2
(-5375 4250);
DISPLAY INVISIBLE (-5375 4250);
FORCEPROP 0 LAST CDS_SEC 1
J 2
(-5375 4250);
DISPLAY INVISIBLE (-5375 4250);
FORCEPROP 1 LASTPIN (-5500 4200) $PN 1
J 2
(-5512 4212);
DISPLAY 0.787234 (-5512 4212);
PAINT MONO (-5512 4212);
DISPLAY INVISIBLE (-5512 4212);
FORCEPROP 1 LASTPIN (-5700 4200) $PN 2
J 2
(-5662 4212);
DISPLAY 0.787234 (-5662 4212);
PAINT MONO (-5662 4212);
DISPLAY INVISIBLE (-5662 4212);
FORCEPROP 1 LAST VALUE 0
J 0
(-5750 4200);
DISPLAY 0.510638 (-5750 4200);
FORCEPROP 1 LAST TOLERANCE 5%
J 2
(-5775 4200);
DISPLAY 0.510638 (-5775 4200);
FORCEPROP 1 LAST MATERIAL CHIP
J 2
(-5850 4200);
DISPLAY 0.510638 (-5850 4200);
FORCEPROP 1 LAST WATTAGE 1/16W
J 0
(-5700 4350);
DISPLAY 0.319149 (-5700 4350);
DISPLAY INVISIBLE (-5700 4350);
FORCEPROP 1 LAST PACK_TYPE 0402LF
J 2
(-5850 4200);
DISPLAY 0.510638 (-5850 4200);
DISPLAY INVISIBLE (-5850 4200);
FORCEPROP 2 LAST CDS_LIB pure_quanta
J 2
(-5600 4200);
DISPLAY INVISIBLE (-5600 4200);
FORCEPROP 1 LAST PATH I30
J 2
(-5550 4350);
DISPLAY 0.978723 (-5550 4350);
PAINT WHITE (-5550 4350);
DISPLAY INVISIBLE (-5550 4350);
FORCEPROP 1 LAST PART_NUMBER CS00002JB13
J 2
(-5525 4325);
DISPLAY 0.319149 (-5525 4325);
DISPLAY INVISIBLE (-5525 4325);
FORCEADD Q_RES..1
R 2
(-5600 4150);
FORCEPROP 1 LAST LOCATION R3715
J 2
(-5375 4150);
DISPLAY 0.510638 (-5375 4150);
FORCEPROP 0 LAST $SEC 1
J 2
(-5375 4200);
DISPLAY INVISIBLE (-5375 4200);
FORCEPROP 0 LAST CDS_SEC 1
J 2
(-5375 4200);
DISPLAY INVISIBLE (-5375 4200);
FORCEPROP 1 LASTPIN (-5500 4150) $PN 1
J 2
(-5512 4162);
DISPLAY 0.787234 (-5512 4162);
PAINT MONO (-5512 4162);
DISPLAY INVISIBLE (-5512 4162);
FORCEPROP 1 LASTPIN (-5700 4150) $PN 2
J 2
(-5662 4162);
DISPLAY 0.787234 (-5662 4162);
PAINT MONO (-5662 4162);
DISPLAY INVISIBLE (-5662 4162);
FORCEPROP 1 LAST TOLERANCE 5%
J 2
(-5775 4150);
DISPLAY 0.510638 (-5775 4150);
FORCEPROP 1 LAST VALUE 0
J 0
(-5750 4150);
DISPLAY 0.510638 (-5750 4150);
FORCEPROP 1 LAST MATERIAL CHIP
J 2
(-5850 4150);
DISPLAY 0.510638 (-5850 4150);
FORCEPROP 2 LAST CDS_LIB pure_quanta
J 2
(-5600 4150);
DISPLAY INVISIBLE (-5600 4150);
FORCEPROP 1 LAST WATTAGE 1/16W
J 0
(-5700 4075);
DISPLAY 0.319149 (-5700 4075);
DISPLAY INVISIBLE (-5700 4075);
FORCEPROP 1 LAST PACK_TYPE 0402LF
J 2
(-5850 4150);
DISPLAY 0.510638 (-5850 4150);
DISPLAY INVISIBLE (-5850 4150);
FORCEPROP 1 LAST PATH I31
J 2
(-5550 4300);
DISPLAY 0.978723 (-5550 4300);
PAINT WHITE (-5550 4300);
DISPLAY INVISIBLE (-5550 4300);
FORCEPROP 1 LAST PART_NUMBER CS00002JB13
J 2
(-5525 4100);
DISPLAY 0.319149 (-5525 4100);
DISPLAY INVISIBLE (-5525 4100);
FORCEADD Q_RES..1
R 2
(-5600 4300);
FORCEPROP 1 LAST LOCATION R3714
J 2
(-5400 4300);
DISPLAY 0.510638 (-5400 4300);
FORCEPROP 2 LAST $SEC 1
J 2
(-5550 4500);
DISPLAY 0.680851 (-5550 4500);
PAINT MONO (-5550 4500);
DISPLAY INVISIBLE (-5550 4500);
FORCEPROP 2 LAST CDS_SEC 1
J 2
(-5550 4500);
DISPLAY 1.021277 (-5550 4500);
DISPLAY INVISIBLE (-5550 4500);
FORCEPROP 1 LASTPIN (-5500 4300) $PN 1
J 2
(-5512 4312);
DISPLAY 0.787234 (-5512 4312);
FORCEPROP 1 LASTPIN (-5700 4300) $PN 2
J 2
(-5662 4312);
DISPLAY 0.787234 (-5662 4312);
FORCEPROP 1 LAST WATTAGE 1/16W
J 0
(-5575 3825);
DISPLAY 0.319149 (-5575 3825);
FORCEPROP 1 LAST PACK_TYPE 0402LF
J 2
(-5625 3825);
DISPLAY 0.319149 (-5625 3825);
FORCEPROP 1 LAST MATERIAL CHIP
J 2
(-5825 4300);
DISPLAY 0.404255 (-5825 4300);
FORCEPROP 1 LAST TOLERANCE 5%
J 2
(-5775 4300);
DISPLAY 0.404255 (-5775 4300);
FORCEPROP 1 LAST VALUE 0
J 0
(-5750 4300);
DISPLAY 0.404255 (-5750 4300);
FORCEPROP 2 LAST CDS_LIB pure_quanta
J 2
(-5600 4300);
PAINT MONO (-5600 4300);
DISPLAY INVISIBLE (-5600 4300);
FORCEPROP 1 LAST PATH I32
J 2
(-5550 4450);
DISPLAY 0.978723 (-5550 4450);
PAINT WHITE (-5550 4450);
DISPLAY INVISIBLE (-5550 4450);
FORCEPROP 1 LAST PART_NUMBER CS00002JB13
J 2
(-5525 3900);
DISPLAY 0.319149 (-5525 3900);
DISPLAY INVISIBLE (-5525 3900);
FORCEADD Q_RES..1
R 2
(-5600 4250);
FORCEPROP 1 LAST LOCATION R3713
J 2
(-5400 4250);
DISPLAY 0.510638 (-5400 4250);
FORCEPROP 2 LAST $SEC 1
J 2
(-5550 4450);
DISPLAY 0.680851 (-5550 4450);
PAINT MONO (-5550 4450);
DISPLAY INVISIBLE (-5550 4450);
FORCEPROP 2 LAST CDS_SEC 1
J 2
(-5550 4450);
DISPLAY 1.021277 (-5550 4450);
DISPLAY INVISIBLE (-5550 4450);
FORCEPROP 1 LASTPIN (-5500 4250) $PN 1
J 2
(-5512 4262);
DISPLAY 0.787234 (-5512 4262);
FORCEPROP 1 LASTPIN (-5700 4250) $PN 2
J 2
(-5662 4262);
DISPLAY 0.787234 (-5662 4262);
FORCEPROP 1 LAST MATERIAL CHIP
J 2
(-5825 4250);
DISPLAY 0.404255 (-5825 4250);
FORCEPROP 1 LAST VALUE 0
J 0
(-5750 4250);
DISPLAY 0.404255 (-5750 4250);
FORCEPROP 1 LAST TOLERANCE 5%
J 2
(-5775 4250);
DISPLAY 0.404255 (-5775 4250);
FORCEPROP 1 LAST WATTAGE 1/16W
J 0
(-5700 4175);
DISPLAY 0.319149 (-5700 4175);
DISPLAY INVISIBLE (-5700 4175);
FORCEPROP 2 LAST CDS_LIB pure_quanta
J 2
(-5600 4250);
PAINT MONO (-5600 4250);
DISPLAY INVISIBLE (-5600 4250);
FORCEPROP 1 LAST PACK_TYPE 0402LF
J 2
(-5850 4250);
DISPLAY 0.404255 (-5850 4250);
DISPLAY INVISIBLE (-5850 4250);
FORCEPROP 1 LAST PATH I33
J 2
(-5550 4400);
DISPLAY 0.978723 (-5550 4400);
PAINT WHITE (-5550 4400);
DISPLAY INVISIBLE (-5550 4400);
FORCEPROP 1 LAST PART_NUMBER CS00002JB13
J 2
(-5525 4200);
DISPLAY 0.319149 (-5525 4200);
DISPLAY INVISIBLE (-5525 4200);
FORCEADD OFFPAGE..4
R 2
(-5350 4500);
FORCEPROP 2 LAST $XR0 253 
J 0
(-5632 4500);
DISPLAY 0.638298 (-5632 4500);
PAINT MONO (-5632 4500);
FORCEPROP 2 LAST CDS_LIB standard
J 2
(-5350 4500);
DISPLAY INVISIBLE (-5350 4500);
FORCEPROP 1 LAST OFFPAGE TRUE
J 2
(-5675 4375);
DISPLAY 0.872340 (-5675 4375);
DISPLAY INVISIBLE (-5675 4375);
FORCEPROP 1 LAST COMMENT_BODY TRUE
J 2
(-5325 4400);
DISPLAY 0.872340 (-5325 4400);
PAINT GREEN (-5325 4400);
DISPLAY INVISIBLE (-5325 4400);
FORCEPROP 2 LAST PATH I34
J 0
(-5600 4550);
DISPLAY 0.680851 (-5600 4550);
DISPLAY INVISIBLE (-5600 4550);
FORCEADD OFFPAGE..1
(-5350 4550);
FORCEPROP 2 LAST $XR0 253 
J 0
(-5632 4550);
DISPLAY 0.638298 (-5632 4550);
PAINT MONO (-5632 4550);
FORCEPROP 2 LAST CDS_LIB standard
J 0
(-5350 4550);
DISPLAY INVISIBLE (-5350 4550);
FORCEPROP 1 LAST OFFPAGE TRUE
J 0
(-5025 4425);
DISPLAY 0.872340 (-5025 4425);
PAINT GREEN (-5025 4425);
DISPLAY INVISIBLE (-5025 4425);
FORCEPROP 1 LAST COMMENT_BODY TRUE
J 0
(-5225 4450);
DISPLAY 0.872340 (-5225 4450);
PAINT GREEN (-5225 4450);
DISPLAY INVISIBLE (-5225 4450);
FORCEPROP 2 LAST PATH I35
J 0
(-5600 4600);
DISPLAY 0.680851 (-5600 4600);
DISPLAY INVISIBLE (-5600 4600);
FORCEADD OFFPAGE..1
(-5350 4600);
FORCEPROP 2 LAST $XR0 253 
J 0
(-5632 4600);
DISPLAY 0.638298 (-5632 4600);
PAINT MONO (-5632 4600);
FORCEPROP 2 LAST CDS_LIB standard
J 0
(-5350 4600);
DISPLAY INVISIBLE (-5350 4600);
FORCEPROP 1 LAST OFFPAGE TRUE
J 0
(-5025 4475);
DISPLAY 0.872340 (-5025 4475);
PAINT GREEN (-5025 4475);
DISPLAY INVISIBLE (-5025 4475);
FORCEPROP 1 LAST COMMENT_BODY TRUE
J 0
(-5225 4500);
DISPLAY 0.872340 (-5225 4500);
PAINT GREEN (-5225 4500);
DISPLAY INVISIBLE (-5225 4500);
FORCEPROP 2 LAST PATH I36
J 0
(-5600 4650);
DISPLAY 0.680851 (-5600 4650);
DISPLAY INVISIBLE (-5600 4650);
FORCEADD UNIVERSAL_GND..1
(-5150 4800);
FORCEPROP 3 LASTPIN (-5150 4850) SIG_NAME GND\g
J 0
(-5140 4860);
DISPLAY 0.659574 (-5140 4860);
PAINT MONO (-5140 4860);
DISPLAY INVISIBLE (-5140 4860);
FORCEPROP 2 LAST CDS_LIB pure_quanta_power
J 0
(-5150 4800);
PAINT MONO (-5150 4800);
DISPLAY INVISIBLE (-5150 4800);
FORCEPROP 1 LAST HDL_POWER GND
J 1
(-5125 4725);
DISPLAY 0.872340 (-5125 4725);
PAINT GREEN (-5125 4725);
DISPLAY INVISIBLE (-5125 4725);
FORCEPROP 1 LAST PATH I37
J 0
(-5075 4800);
DISPLAY 0.872340 (-5075 4800);
PAINT AQUA (-5075 4800);
DISPLAY INVISIBLE (-5075 4800);
FORCEADD Q_CAP..1
(-5150 5025);
FORCEPROP 1 LAST LOCATION C2056
J 0
(-5100 5125);
DISPLAY 0.978723 (-5100 5125);
FORCEPROP 2 LAST $SEC 1
J 0
(-5100 5225);
DISPLAY 0.680851 (-5100 5225);
PAINT MONO (-5100 5225);
DISPLAY INVISIBLE (-5100 5225);
FORCEPROP 2 LAST CDS_SEC 1
J 0
(-5100 5225);
DISPLAY 1.021277 (-5100 5225);
DISPLAY INVISIBLE (-5100 5225);
FORCEPROP 1 LASTPIN (-5150 5125) $PN 1
J 0
(-5140 5105);
DISPLAY 0.787234 (-5140 5105);
FORCEPROP 1 LASTPIN (-5150 4925) $PN 2
J 0
(-5140 4905);
DISPLAY 0.787234 (-5140 4905);
FORCEPROP 1 LAST PACK_TYPE 0402
J 0
(-5100 4825);
DISPLAY 0.510638 (-5100 4825);
FORCEPROP 1 LAST MATERIAL X7R
J 0
(-5100 4925);
DISPLAY 0.510638 (-5100 4925);
FORCEPROP 1 LAST TOLERANCE 10%
J 0
(-5100 4975);
DISPLAY 0.510638 (-5100 4975);
FORCEPROP 1 LAST VALUE 0.1UF
J 0
(-5100 5075);
DISPLAY 0.510638 (-5100 5075);
FORCEPROP 1 LAST VOLTAGE 25V
J 0
(-5100 5025);
DISPLAY 0.510638 (-5100 5025);
FORCEPROP 2 LAST CDS_LIB pure_quanta
J 2
(-5150 5025);
PAINT MONO (-5150 5025);
DISPLAY INVISIBLE (-5150 5025);
FORCEPROP 1 LAST PATH I38
J 0
(-5100 5175);
DISPLAY 0.978723 (-5100 5175);
PAINT WHITE (-5100 5175);
DISPLAY INVISIBLE (-5100 5175);
FORCEPROP 1 LAST PART_NUMBER CH4104K1B00
J 0
(-5100 4875);
DISPLAY 0.510638 (-5100 4875);
DISPLAY INVISIBLE (-5100 4875);
FORCEADD UNIVERSAL_POWER..1
(-5150 5350);
FORCEPROP 3 LASTPIN (-5150 5300) SIG_NAME P3V3_AUX\g
J 0
(-5140 5310);
DISPLAY 0.659574 (-5140 5310);
PAINT MONO (-5140 5310);
DISPLAY INVISIBLE (-5140 5310);
FORCEPROP 1 LAST HDL_POWER P3V3_AUX
J 1
(-5150 5400);
DISPLAY 0.872340 (-5150 5400);
PAINT GREEN (-5150 5400);
FORCEPROP 2 LAST CDS_LIB pure_quanta_power
J 0
(-5150 5350);
PAINT MONO (-5150 5350);
DISPLAY INVISIBLE (-5150 5350);
FORCEPROP 1 LAST PATH I39
J 0
(-5100 5375);
DISPLAY 0.872340 (-5100 5375);
PAINT AQUA (-5100 5375);
DISPLAY INVISIBLE (-5100 5375);
FORCEADD Q_RES..2
(-6300 2200);
FORCEPROP 1 LAST LOCATION R3707
J 0
(-6255 2325);
DISPLAY 0.978723 (-6255 2325);
FORCEPROP 2 LAST $SEC 1
J 0
(-6250 2425);
DISPLAY 0.680851 (-6250 2425);
PAINT MONO (-6250 2425);
DISPLAY INVISIBLE (-6250 2425);
FORCEPROP 2 LAST CDS_SEC 1
J 0
(-6250 2425);
DISPLAY 1.021277 (-6250 2425);
DISPLAY INVISIBLE (-6250 2425);
FORCEPROP 1 LASTPIN (-6300 2300) $PN 1
J 0
(-6295 2262);
DISPLAY 0.787234 (-6295 2262);
FORCEPROP 1 LASTPIN (-6300 2100) $PN 2
J 0
(-6295 2110);
DISPLAY 0.787234 (-6295 2110);
FORCEPROP 1 LAST TOLERANCE 1%
J 0
(-6255 2225);
DISPLAY 0.638298 (-6255 2225);
FORCEPROP 1 LAST WATTAGE 1/16W
J 0
(-6260 2175);
DISPLAY 0.638298 (-6260 2175);
FORCEPROP 1 LAST MATERIAL CHIP
J 0
(-6260 2125);
DISPLAY 0.638298 (-6260 2125);
FORCEPROP 1 LAST VALUE 1K
J 0
(-6255 2275);
DISPLAY 0.638298 (-6255 2275);
FORCEPROP 1 LAST PACK_TYPE 0402LF
J 0
(-6260 2075);
DISPLAY 0.638298 (-6260 2075);
FORCEPROP 2 LAST CDS_LIB pure_quanta
J 0
(-6300 2200);
PAINT MONO (-6300 2200);
DISPLAY INVISIBLE (-6300 2200);
FORCEPROP 1 LAST PATH I4
J 0
(-6250 2375);
DISPLAY 0.978723 (-6250 2375);
PAINT WHITE (-6250 2375);
DISPLAY INVISIBLE (-6250 2375);
FORCEPROP 1 LAST PART_NUMBER CS21002FB06
J 0
(-6260 2075);
DISPLAY 0.510638 (-6260 2075);
DISPLAY INVISIBLE (-6260 2075);
FORCEADD Q_RES..1
(-2550 1275);
FORCEPROP 1 LAST LOCATION R4270
J 0
(-2800 1275);
DISPLAY 0.510638 (-2800 1275);
FORCEPROP 0 LAST $SEC 1
J 0
(-2175 1325);
DISPLAY INVISIBLE (-2175 1325);
FORCEPROP 0 LAST CDS_SEC 1
J 0
(-2175 1325);
DISPLAY INVISIBLE (-2175 1325);
FORCEPROP 1 LASTPIN (-2650 1275) $PN 1
J 0
(-2638 1287);
DISPLAY 0.787234 (-2638 1287);
PAINT MONO (-2638 1287);
DISPLAY INVISIBLE (-2638 1287);
FORCEPROP 1 LASTPIN (-2450 1275) $PN 2
J 0
(-2488 1287);
DISPLAY 0.787234 (-2488 1287);
PAINT MONO (-2488 1287);
DISPLAY INVISIBLE (-2488 1287);
FORCEPROP 1 LAST MATERIAL EMPTY
J 0
(-2175 1275);
DISPLAY 0.638298 (-2175 1275);
PAINT RED (-2175 1275);
FORCEPROP 1 LAST TOLERANCE 5%
J 0
(-2275 1275);
DISPLAY 0.638298 (-2275 1275);
FORCEPROP 1 LAST VALUE 2.2K
J 2
(-2275 1275);
DISPLAY 0.638298 (-2275 1275);
FORCEPROP 2 LAST CDS_LIB pure_quanta
J 0
(-2550 1275);
DISPLAY INVISIBLE (-2550 1275);
FORCEPROP 1 LAST PACK_TYPE 0402LF
J 0
(-2650 1375);
DISPLAY 0.510638 (-2650 1375);
DISPLAY INVISIBLE (-2650 1375);
FORCEPROP 1 LAST WATTAGE 1/16W
J 2
(-2350 1375);
DISPLAY 0.510638 (-2350 1375);
DISPLAY INVISIBLE (-2350 1375);
FORCEPROP 1 LAST PATH I40
J 0
(-2600 1425);
DISPLAY 0.978723 (-2600 1425);
PAINT WHITE (-2600 1425);
DISPLAY INVISIBLE (-2600 1425);
FORCEPROP 1 LAST PART_NUMBER CS22202JB07
J 0
(-2650 1325);
DISPLAY 0.510638 (-2650 1325);
DISPLAY INVISIBLE (-2650 1325);
FORCEADD Q_RES..1
(-2550 1325);
FORCEPROP 1 LAST LOCATION R4269
J 0
(-2800 1325);
DISPLAY 0.510638 (-2800 1325);
FORCEPROP 0 LAST $SEC 1
J 0
(-2400 1475);
DISPLAY INVISIBLE (-2400 1475);
FORCEPROP 0 LAST CDS_SEC 1
J 0
(-2400 1475);
DISPLAY INVISIBLE (-2400 1475);
FORCEPROP 1 LASTPIN (-2650 1325) $PN 1
J 0
(-2638 1337);
DISPLAY 0.787234 (-2638 1337);
PAINT MONO (-2638 1337);
DISPLAY INVISIBLE (-2638 1337);
FORCEPROP 1 LASTPIN (-2450 1325) $PN 2
J 0
(-2488 1337);
DISPLAY 0.787234 (-2488 1337);
PAINT MONO (-2488 1337);
DISPLAY INVISIBLE (-2488 1337);
FORCEPROP 1 LAST MATERIAL EMPTY
J 0
(-2175 1325);
DISPLAY 0.638298 (-2175 1325);
PAINT RED (-2175 1325);
FORCEPROP 1 LAST PACK_TYPE 0402LF
J 0
(-2700 1450);
DISPLAY 0.510638 (-2700 1450);
FORCEPROP 1 LAST TOLERANCE 5%
J 0
(-2275 1325);
DISPLAY 0.638298 (-2275 1325);
FORCEPROP 1 LAST VALUE 2.2K
J 2
(-2275 1325);
DISPLAY 0.638298 (-2275 1325);
FORCEPROP 1 LAST WATTAGE 1/16W
J 2
(-2400 1450);
DISPLAY 0.510638 (-2400 1450);
FORCEPROP 2 LAST CDS_LIB pure_quanta
J 0
(-2550 1325);
DISPLAY INVISIBLE (-2550 1325);
FORCEPROP 1 LAST PATH I41
J 0
(-2600 1475);
DISPLAY 0.978723 (-2600 1475);
PAINT WHITE (-2600 1475);
DISPLAY INVISIBLE (-2600 1475);
FORCEPROP 1 LAST PART_NUMBER CS22202JB07
J 0
(-2700 1400);
DISPLAY 0.510638 (-2700 1400);
DISPLAY INVISIBLE (-2700 1400);
FORCEADD Q_RES..1
(-2550 1525);
FORCEPROP 1 LAST LOCATION R3732
J 0
(-2800 1525);
DISPLAY 0.638298 (-2800 1525);
FORCEPROP 2 LAST $SEC 1
J 0
(-2600 1725);
DISPLAY 0.680851 (-2600 1725);
PAINT MONO (-2600 1725);
DISPLAY INVISIBLE (-2600 1725);
FORCEPROP 2 LAST CDS_SEC 1
J 0
(-2600 1725);
DISPLAY 1.021277 (-2600 1725);
DISPLAY INVISIBLE (-2600 1725);
FORCEPROP 1 LASTPIN (-2650 1525) $PN 1
J 0
(-2638 1537);
DISPLAY 0.787234 (-2638 1537);
FORCEPROP 1 LASTPIN (-2450 1525) $PN 2
J 0
(-2488 1537);
DISPLAY 0.787234 (-2488 1537);
FORCEPROP 1 LAST TOLERANCE 5%
J 0
(-2300 1525);
DISPLAY 0.510638 (-2300 1525);
FORCEPROP 1 LAST MATERIAL CHIP
J 0
(-2200 1525);
DISPLAY 0.510638 (-2200 1525);
FORCEPROP 1 LAST VALUE 2.2K
J 2
(-2300 1525);
DISPLAY 0.510638 (-2300 1525);
FORCEPROP 1 LAST WATTAGE 1/16W
J 2
(-2350 1625);
DISPLAY 0.510638 (-2350 1625);
DISPLAY INVISIBLE (-2350 1625);
FORCEPROP 1 LAST PACK_TYPE 0402LF
J 0
(-2650 1625);
DISPLAY 0.510638 (-2650 1625);
DISPLAY INVISIBLE (-2650 1625);
FORCEPROP 2 LAST CDS_LIB pure_quanta
J 0
(-2550 1525);
PAINT MONO (-2550 1525);
DISPLAY INVISIBLE (-2550 1525);
FORCEPROP 1 LAST PATH I42
J 0
(-2600 1675);
DISPLAY 0.978723 (-2600 1675);
PAINT WHITE (-2600 1675);
DISPLAY INVISIBLE (-2600 1675);
FORCEPROP 1 LAST PART_NUMBER CS22202JB07
J 0
(-2650 1575);
DISPLAY 0.510638 (-2650 1575);
DISPLAY INVISIBLE (-2650 1575);
FORCEADD Q_RES..1
(-2550 1575);
FORCEPROP 1 LAST LOCATION R3731
J 0
(-2800 1575);
DISPLAY 0.638298 (-2800 1575);
FORCEPROP 2 LAST $SEC 1
J 0
(-2600 1775);
DISPLAY 0.680851 (-2600 1775);
PAINT MONO (-2600 1775);
DISPLAY INVISIBLE (-2600 1775);
FORCEPROP 2 LAST CDS_SEC 1
J 0
(-2600 1775);
DISPLAY 1.021277 (-2600 1775);
DISPLAY INVISIBLE (-2600 1775);
FORCEPROP 1 LASTPIN (-2650 1575) $PN 1
J 0
(-2638 1587);
DISPLAY 0.787234 (-2638 1587);
FORCEPROP 1 LASTPIN (-2450 1575) $PN 2
J 0
(-2488 1587);
DISPLAY 0.787234 (-2488 1587);
FORCEPROP 1 LAST MATERIAL CHIP
J 0
(-2200 1575);
DISPLAY 0.510638 (-2200 1575);
FORCEPROP 1 LAST TOLERANCE 5%
J 0
(-2300 1575);
DISPLAY 0.510638 (-2300 1575);
FORCEPROP 1 LAST PACK_TYPE 0402LF
J 0
(-2700 1700);
DISPLAY 0.510638 (-2700 1700);
FORCEPROP 1 LAST VALUE 2.2K
J 2
(-2300 1575);
DISPLAY 0.510638 (-2300 1575);
FORCEPROP 1 LAST WATTAGE 1/16W
J 2
(-2400 1700);
DISPLAY 0.510638 (-2400 1700);
FORCEPROP 2 LAST CDS_LIB pure_quanta
J 0
(-2550 1575);
PAINT MONO (-2550 1575);
DISPLAY INVISIBLE (-2550 1575);
FORCEPROP 1 LAST PATH I43
J 0
(-2600 1725);
DISPLAY 0.978723 (-2600 1725);
PAINT WHITE (-2600 1725);
DISPLAY INVISIBLE (-2600 1725);
FORCEPROP 1 LAST PART_NUMBER CS22202JB07
J 0
(-2700 1650);
DISPLAY 0.510638 (-2700 1650);
DISPLAY INVISIBLE (-2700 1650);
FORCEADD Q_RES..1
(-2550 1875);
FORCEPROP 1 LAST LOCATION R3729
J 0
(-2800 1875);
DISPLAY 0.510638 (-2800 1875);
FORCEPROP 2 LAST $SEC 1
J 0
(-2600 2075);
DISPLAY 0.680851 (-2600 2075);
PAINT MONO (-2600 2075);
DISPLAY INVISIBLE (-2600 2075);
FORCEPROP 2 LAST CDS_SEC 1
J 0
(-2600 2075);
DISPLAY 1.021277 (-2600 2075);
DISPLAY INVISIBLE (-2600 2075);
FORCEPROP 1 LASTPIN (-2650 1875) $PN 1
J 0
(-2638 1887);
DISPLAY 0.787234 (-2638 1887);
FORCEPROP 1 LASTPIN (-2450 1875) $PN 2
J 0
(-2488 1887);
DISPLAY 0.787234 (-2488 1887);
FORCEPROP 1 LAST TOLERANCE 5%
J 0
(-2325 1875);
DISPLAY 0.510638 (-2325 1875);
FORCEPROP 1 LAST MATERIAL CHIP
J 0
(-2250 1875);
DISPLAY 0.510638 (-2250 1875);
FORCEPROP 1 LAST PACK_TYPE 0402LF
J 0
(-2700 2000);
DISPLAY 0.510638 (-2700 2000);
FORCEPROP 1 LAST WATTAGE 1/16W
J 2
(-2400 2000);
DISPLAY 0.510638 (-2400 2000);
FORCEPROP 1 LAST VALUE 2.2K
J 2
(-2325 1875);
DISPLAY 0.510638 (-2325 1875);
FORCEPROP 2 LAST CDS_LIB pure_quanta
J 0
(-2550 1875);
PAINT MONO (-2550 1875);
DISPLAY INVISIBLE (-2550 1875);
FORCEPROP 1 LAST PATH I44
J 0
(-2600 2025);
DISPLAY 0.978723 (-2600 2025);
PAINT WHITE (-2600 2025);
DISPLAY INVISIBLE (-2600 2025);
FORCEPROP 1 LAST PART_NUMBER CS22202JB07
J 0
(-2700 1950);
DISPLAY 0.510638 (-2700 1950);
DISPLAY INVISIBLE (-2700 1950);
FORCEADD Q_RES..1
(-2550 1825);
FORCEPROP 1 LAST LOCATION R3730
J 0
(-2800 1825);
DISPLAY 0.510638 (-2800 1825);
FORCEPROP 2 LAST $SEC 1
J 0
(-2600 2025);
DISPLAY 0.680851 (-2600 2025);
PAINT MONO (-2600 2025);
DISPLAY INVISIBLE (-2600 2025);
FORCEPROP 2 LAST CDS_SEC 1
J 0
(-2600 2025);
DISPLAY 1.021277 (-2600 2025);
DISPLAY INVISIBLE (-2600 2025);
FORCEPROP 1 LASTPIN (-2650 1825) $PN 1
J 0
(-2638 1837);
DISPLAY 0.787234 (-2638 1837);
FORCEPROP 1 LASTPIN (-2450 1825) $PN 2
J 0
(-2488 1837);
DISPLAY 0.787234 (-2488 1837);
FORCEPROP 1 LAST MATERIAL CHIP
J 0
(-2250 1825);
DISPLAY 0.510638 (-2250 1825);
FORCEPROP 1 LAST TOLERANCE 5%
J 0
(-2325 1825);
DISPLAY 0.510638 (-2325 1825);
FORCEPROP 1 LAST VALUE 2.2K
J 2
(-2325 1825);
DISPLAY 0.510638 (-2325 1825);
FORCEPROP 2 LAST CDS_LIB pure_quanta
J 0
(-2550 1825);
PAINT MONO (-2550 1825);
DISPLAY INVISIBLE (-2550 1825);
FORCEPROP 1 LAST PACK_TYPE 0402LF
J 0
(-2650 1925);
DISPLAY 0.510638 (-2650 1925);
DISPLAY INVISIBLE (-2650 1925);
FORCEPROP 1 LAST WATTAGE 1/16W
J 2
(-2350 1925);
DISPLAY 0.510638 (-2350 1925);
DISPLAY INVISIBLE (-2350 1925);
FORCEPROP 1 LAST PATH I45
J 0
(-2600 1975);
DISPLAY 0.978723 (-2600 1975);
PAINT WHITE (-2600 1975);
DISPLAY INVISIBLE (-2600 1975);
FORCEPROP 1 LAST PART_NUMBER CS22202JB07
J 0
(-2650 1875);
DISPLAY 0.510638 (-2650 1875);
DISPLAY INVISIBLE (-2650 1875);
FORCEADD UNIVERSAL_GND..1
(-3825 3675);
FORCEPROP 3 LASTPIN (-3825 3725) SIG_NAME GND\g
J 0
(-3815 3735);
DISPLAY 0.659574 (-3815 3735);
PAINT MONO (-3815 3735);
DISPLAY INVISIBLE (-3815 3735);
FORCEPROP 2 LAST CDS_LIB pure_quanta_power
J 0
(-3825 3675);
DISPLAY INVISIBLE (-3825 3675);
FORCEPROP 1 LAST HDL_POWER GND
J 1
(-3800 3600);
DISPLAY 0.872340 (-3800 3600);
PAINT GREEN (-3800 3600);
DISPLAY INVISIBLE (-3800 3600);
FORCEPROP 1 LAST PATH I46
J 0
(-3750 3675);
DISPLAY 0.872340 (-3750 3675);
PAINT AQUA (-3750 3675);
DISPLAY INVISIBLE (-3750 3675);
FORCEADD Q_RES..1
(-2575 2125);
FORCEPROP 1 LAST LOCATION R3728
J 0
(-2825 2125);
DISPLAY 0.510638 (-2825 2125);
FORCEPROP 0 LAST $SEC 1
J 0
(-2200 2175);
DISPLAY INVISIBLE (-2200 2175);
FORCEPROP 0 LAST CDS_SEC 1
J 0
(-2200 2175);
DISPLAY INVISIBLE (-2200 2175);
FORCEPROP 1 LASTPIN (-2675 2125) $PN 1
J 0
(-2663 2137);
DISPLAY 0.787234 (-2663 2137);
PAINT MONO (-2663 2137);
DISPLAY INVISIBLE (-2663 2137);
FORCEPROP 1 LASTPIN (-2475 2125) $PN 2
J 0
(-2513 2137);
DISPLAY 0.787234 (-2513 2137);
PAINT MONO (-2513 2137);
DISPLAY INVISIBLE (-2513 2137);
FORCEPROP 1 LAST MATERIAL CHIP
J 0
(-2200 2125);
DISPLAY 0.638298 (-2200 2125);
FORCEPROP 1 LAST VALUE 2.2K
J 2
(-2300 2125);
DISPLAY 0.638298 (-2300 2125);
FORCEPROP 1 LAST TOLERANCE 5%
J 0
(-2300 2125);
DISPLAY 0.638298 (-2300 2125);
FORCEPROP 2 LAST CDS_LIB pure_quanta
J 0
(-2575 2125);
DISPLAY INVISIBLE (-2575 2125);
FORCEPROP 1 LAST PACK_TYPE 0402LF
J 0
(-2675 2225);
DISPLAY 0.510638 (-2675 2225);
DISPLAY INVISIBLE (-2675 2225);
FORCEPROP 1 LAST WATTAGE 1/16W
J 2
(-2375 2225);
DISPLAY 0.510638 (-2375 2225);
DISPLAY INVISIBLE (-2375 2225);
FORCEPROP 1 LAST PATH I47
J 0
(-2625 2275);
DISPLAY 0.978723 (-2625 2275);
PAINT WHITE (-2625 2275);
DISPLAY INVISIBLE (-2625 2275);
FORCEPROP 1 LAST PART_NUMBER CS22202JB07
J 0
(-2675 2175);
DISPLAY 0.510638 (-2675 2175);
DISPLAY INVISIBLE (-2675 2175);
FORCEADD Q_RES..1
(-2575 2175);
FORCEPROP 1 LAST LOCATION R3727
J 0
(-2825 2175);
DISPLAY 0.510638 (-2825 2175);
FORCEPROP 0 LAST $SEC 1
J 0
(-2425 2325);
DISPLAY INVISIBLE (-2425 2325);
FORCEPROP 0 LAST CDS_SEC 1
J 0
(-2425 2325);
DISPLAY INVISIBLE (-2425 2325);
FORCEPROP 1 LASTPIN (-2675 2175) $PN 1
J 0
(-2663 2187);
DISPLAY 0.787234 (-2663 2187);
PAINT MONO (-2663 2187);
DISPLAY INVISIBLE (-2663 2187);
FORCEPROP 1 LASTPIN (-2475 2175) $PN 2
J 0
(-2513 2187);
DISPLAY 0.787234 (-2513 2187);
PAINT MONO (-2513 2187);
DISPLAY INVISIBLE (-2513 2187);
FORCEPROP 1 LAST PACK_TYPE 0402LF
J 0
(-2725 2300);
DISPLAY 0.510638 (-2725 2300);
FORCEPROP 1 LAST VALUE 2.2K
J 2
(-2300 2175);
DISPLAY 0.638298 (-2300 2175);
FORCEPROP 1 LAST TOLERANCE 5%
J 0
(-2300 2175);
DISPLAY 0.638298 (-2300 2175);
FORCEPROP 1 LAST WATTAGE 1/16W
J 2
(-2425 2300);
DISPLAY 0.510638 (-2425 2300);
FORCEPROP 1 LAST MATERIAL CHIP
J 0
(-2200 2175);
DISPLAY 0.638298 (-2200 2175);
FORCEPROP 2 LAST CDS_LIB pure_quanta
J 0
(-2575 2175);
DISPLAY INVISIBLE (-2575 2175);
FORCEPROP 1 LAST PATH I48
J 0
(-2625 2325);
DISPLAY 0.978723 (-2625 2325);
PAINT WHITE (-2625 2325);
DISPLAY INVISIBLE (-2625 2325);
FORCEPROP 1 LAST PART_NUMBER CS22202JB07
J 0
(-2725 2250);
DISPLAY 0.510638 (-2725 2250);
DISPLAY INVISIBLE (-2725 2250);
FORCEADD Q_RES..1
(-2575 2400);
FORCEPROP 1 LAST LOCATION R3726
J 0
(-2825 2400);
DISPLAY 0.510638 (-2825 2400);
FORCEPROP 0 LAST $SEC 1
J 0
(-2200 2450);
DISPLAY INVISIBLE (-2200 2450);
FORCEPROP 0 LAST CDS_SEC 1
J 0
(-2200 2450);
DISPLAY INVISIBLE (-2200 2450);
FORCEPROP 1 LASTPIN (-2675 2400) $PN 1
J 0
(-2663 2412);
DISPLAY 0.787234 (-2663 2412);
PAINT MONO (-2663 2412);
DISPLAY INVISIBLE (-2663 2412);
FORCEPROP 1 LASTPIN (-2475 2400) $PN 2
J 0
(-2513 2412);
DISPLAY 0.787234 (-2513 2412);
PAINT MONO (-2513 2412);
DISPLAY INVISIBLE (-2513 2412);
FORCEPROP 1 LAST TOLERANCE 5%
J 0
(-2300 2400);
DISPLAY 0.638298 (-2300 2400);
FORCEPROP 1 LAST MATERIAL CHIP
J 0
(-2200 2400);
DISPLAY 0.638298 (-2200 2400);
FORCEPROP 1 LAST VALUE 2.2K
J 2
(-2300 2400);
DISPLAY 0.638298 (-2300 2400);
FORCEPROP 1 LAST WATTAGE 1/16W
J 2
(-2375 2500);
DISPLAY 0.510638 (-2375 2500);
DISPLAY INVISIBLE (-2375 2500);
FORCEPROP 1 LAST PACK_TYPE 0402LF
J 0
(-2675 2500);
DISPLAY 0.510638 (-2675 2500);
DISPLAY INVISIBLE (-2675 2500);
FORCEPROP 2 LAST CDS_LIB pure_quanta
J 0
(-2575 2400);
DISPLAY INVISIBLE (-2575 2400);
FORCEPROP 1 LAST PATH I49
J 0
(-2625 2550);
DISPLAY 0.978723 (-2625 2550);
PAINT WHITE (-2625 2550);
DISPLAY INVISIBLE (-2625 2550);
FORCEPROP 1 LAST PART_NUMBER CS22202JB07
J 0
(-2675 2450);
DISPLAY 0.510638 (-2675 2450);
DISPLAY INVISIBLE (-2675 2450);
FORCEADD UNIVERSAL_GND..1
(-6025 1975);
FORCEPROP 3 LASTPIN (-6025 2025) SIG_NAME GND\g
J 0
(-6015 2035);
DISPLAY 0.659574 (-6015 2035);
PAINT MONO (-6015 2035);
DISPLAY INVISIBLE (-6015 2035);
FORCEPROP 2 LAST ROOM IO_SLOT
J 1
(-6250 2050);
DISPLAY 0.744681 (-6250 2050);
FORCEPROP 2 LAST CDS_LIB pure_quanta_power
J 0
(-6025 1975);
PAINT MONO (-6025 1975);
DISPLAY INVISIBLE (-6025 1975);
FORCEPROP 1 LAST HDL_POWER GND
J 1
(-6000 1900);
DISPLAY 0.872340 (-6000 1900);
PAINT GREEN (-6000 1900);
DISPLAY INVISIBLE (-6000 1900);
FORCEPROP 1 LAST PATH I5
J 0
(-5950 1975);
DISPLAY 0.872340 (-5950 1975);
PAINT AQUA (-5950 1975);
DISPLAY INVISIBLE (-5950 1975);
FORCEADD Q_RES..1
(-2575 2450);
FORCEPROP 1 LAST LOCATION R3725
J 0
(-2825 2450);
DISPLAY 0.510638 (-2825 2450);
FORCEPROP 0 LAST $SEC 1
J 0
(-2425 2600);
DISPLAY INVISIBLE (-2425 2600);
FORCEPROP 0 LAST CDS_SEC 1
J 0
(-2425 2600);
DISPLAY INVISIBLE (-2425 2600);
FORCEPROP 1 LASTPIN (-2675 2450) $PN 1
J 0
(-2663 2462);
DISPLAY 0.787234 (-2663 2462);
PAINT MONO (-2663 2462);
DISPLAY INVISIBLE (-2663 2462);
FORCEPROP 1 LASTPIN (-2475 2450) $PN 2
J 0
(-2513 2462);
DISPLAY 0.787234 (-2513 2462);
PAINT MONO (-2513 2462);
DISPLAY INVISIBLE (-2513 2462);
FORCEPROP 1 LAST PACK_TYPE 0402LF
J 0
(-2725 2575);
DISPLAY 0.510638 (-2725 2575);
FORCEPROP 1 LAST TOLERANCE 5%
J 0
(-2300 2450);
DISPLAY 0.638298 (-2300 2450);
FORCEPROP 1 LAST MATERIAL CHIP
J 0
(-2200 2450);
DISPLAY 0.638298 (-2200 2450);
FORCEPROP 1 LAST WATTAGE 1/16W
J 2
(-2425 2575);
DISPLAY 0.510638 (-2425 2575);
FORCEPROP 1 LAST VALUE 2.2K
J 2
(-2300 2450);
DISPLAY 0.638298 (-2300 2450);
FORCEPROP 2 LAST CDS_LIB pure_quanta
J 0
(-2575 2450);
DISPLAY INVISIBLE (-2575 2450);
FORCEPROP 1 LAST PATH I50
J 0
(-2625 2600);
DISPLAY 0.978723 (-2625 2600);
PAINT WHITE (-2625 2600);
DISPLAY INVISIBLE (-2625 2600);
FORCEPROP 1 LAST PART_NUMBER CS22202JB07
J 0
(-2725 2525);
DISPLAY 0.510638 (-2725 2525);
DISPLAY INVISIBLE (-2725 2525);
FORCEADD UNIVERSAL_POWER..1
(-3000 3025);
FORCEPROP 3 LASTPIN (-3000 2975) SIG_NAME P3V3_AUX\g
J 0
(-2990 2985);
DISPLAY 0.659574 (-2990 2985);
PAINT MONO (-2990 2985);
DISPLAY INVISIBLE (-2990 2985);
FORCEPROP 1 LAST HDL_POWER P3V3_AUX
J 1
(-3000 3075);
DISPLAY 0.872340 (-3000 3075);
PAINT GREEN (-3000 3075);
FORCEPROP 2 LAST CDS_LIB pure_quanta_power
J 0
(-3000 3025);
PAINT MONO (-3000 3025);
DISPLAY INVISIBLE (-3000 3025);
FORCEPROP 1 LAST PATH I51
J 0
(-2950 3050);
DISPLAY 0.872340 (-2950 3050);
PAINT AQUA (-2950 3050);
DISPLAY INVISIBLE (-2950 3050);
FORCEADD Q_RES..1
(-2575 2775);
FORCEPROP 1 LAST LOCATION R3724
J 0
(-2825 2775);
DISPLAY 0.510638 (-2825 2775);
FORCEPROP 0 LAST $SEC 1
J 0
(-2200 2825);
DISPLAY INVISIBLE (-2200 2825);
FORCEPROP 0 LAST CDS_SEC 1
J 0
(-2200 2825);
DISPLAY INVISIBLE (-2200 2825);
FORCEPROP 1 LASTPIN (-2675 2775) $PN 1
J 0
(-2663 2787);
DISPLAY 0.787234 (-2663 2787);
PAINT MONO (-2663 2787);
DISPLAY INVISIBLE (-2663 2787);
FORCEPROP 1 LASTPIN (-2475 2775) $PN 2
J 0
(-2513 2787);
DISPLAY 0.787234 (-2513 2787);
PAINT MONO (-2513 2787);
DISPLAY INVISIBLE (-2513 2787);
FORCEPROP 1 LAST TOLERANCE 5%
J 0
(-2300 2775);
DISPLAY 0.638298 (-2300 2775);
FORCEPROP 1 LAST MATERIAL CHIP
J 0
(-2200 2775);
DISPLAY 0.638298 (-2200 2775);
FORCEPROP 1 LAST VALUE 2.2K
J 2
(-2300 2775);
DISPLAY 0.638298 (-2300 2775);
FORCEPROP 2 LAST CDS_LIB pure_quanta
J 0
(-2575 2775);
DISPLAY INVISIBLE (-2575 2775);
FORCEPROP 1 LAST PACK_TYPE 0402LF
J 0
(-2675 2875);
DISPLAY 0.510638 (-2675 2875);
DISPLAY INVISIBLE (-2675 2875);
FORCEPROP 1 LAST WATTAGE 1/16W
J 2
(-2375 2875);
DISPLAY 0.510638 (-2375 2875);
DISPLAY INVISIBLE (-2375 2875);
FORCEPROP 1 LAST PATH I52
J 0
(-2625 2925);
DISPLAY 0.978723 (-2625 2925);
PAINT WHITE (-2625 2925);
DISPLAY INVISIBLE (-2625 2925);
FORCEPROP 1 LAST PART_NUMBER CS22202JB07
J 0
(-2675 2825);
DISPLAY 0.510638 (-2675 2825);
DISPLAY INVISIBLE (-2675 2825);
FORCEADD Q_RES..1
(-2575 2825);
FORCEPROP 1 LAST LOCATION R3723
J 0
(-2825 2825);
DISPLAY 0.510638 (-2825 2825);
FORCEPROP 0 LAST $SEC 1
J 0
(-2425 2975);
DISPLAY INVISIBLE (-2425 2975);
FORCEPROP 0 LAST CDS_SEC 1
J 0
(-2425 2975);
DISPLAY INVISIBLE (-2425 2975);
FORCEPROP 1 LASTPIN (-2675 2825) $PN 1
J 0
(-2663 2837);
DISPLAY 0.787234 (-2663 2837);
PAINT MONO (-2663 2837);
DISPLAY INVISIBLE (-2663 2837);
FORCEPROP 1 LASTPIN (-2475 2825) $PN 2
J 0
(-2513 2837);
DISPLAY 0.787234 (-2513 2837);
PAINT MONO (-2513 2837);
DISPLAY INVISIBLE (-2513 2837);
FORCEPROP 1 LAST PACK_TYPE 0402LF
J 0
(-2725 2950);
DISPLAY 0.510638 (-2725 2950);
FORCEPROP 1 LAST MATERIAL CHIP
J 0
(-2200 2825);
DISPLAY 0.638298 (-2200 2825);
FORCEPROP 1 LAST WATTAGE 1/16W
J 2
(-2425 2950);
DISPLAY 0.510638 (-2425 2950);
FORCEPROP 1 LAST VALUE 2.2K
J 2
(-2300 2825);
DISPLAY 0.638298 (-2300 2825);
FORCEPROP 1 LAST TOLERANCE 5%
J 0
(-2300 2825);
DISPLAY 0.638298 (-2300 2825);
FORCEPROP 2 LAST CDS_LIB pure_quanta
J 0
(-2575 2825);
DISPLAY INVISIBLE (-2575 2825);
FORCEPROP 1 LAST PATH I53
J 0
(-2625 2975);
DISPLAY 0.978723 (-2625 2975);
PAINT WHITE (-2625 2975);
DISPLAY INVISIBLE (-2625 2975);
FORCEPROP 1 LAST PART_NUMBER CS22202JB07
J 0
(-2725 2900);
DISPLAY 0.510638 (-2725 2900);
DISPLAY INVISIBLE (-2725 2900);
FORCEADD OFFPAGE..2
(-1175 1275);
FORCEPROP 2 LAST $XR1 253 
J 0
(-866 1275);
DISPLAY 0.638298 (-866 1275);
PAINT MONO (-866 1275);
FORCEPROP 2 LAST $XR0 150 
J 0
(-986 1275);
DISPLAY 0.638298 (-986 1275);
PAINT MONO (-986 1275);
FORCEPROP 2 LAST CDS_LIB standard
J 0
(-1175 1275);
PAINT MONO (-1175 1275);
DISPLAY INVISIBLE (-1175 1275);
FORCEPROP 1 LAST OFFPAGE TRUE
J 0
(-850 1150);
DISPLAY 0.872340 (-850 1150);
PAINT GREEN (-850 1150);
DISPLAY INVISIBLE (-850 1150);
FORCEPROP 1 LAST COMMENT_BODY TRUE
J 0
(-1220 1180);
DISPLAY 0.872340 (-1220 1180);
PAINT GREEN (-1220 1180);
DISPLAY INVISIBLE (-1220 1180);
FORCEPROP 2 LAST PATH I54
J 0
(-1000 1350);
DISPLAY 0.680851 (-1000 1350);
DISPLAY INVISIBLE (-1000 1350);
FORCEADD OFFPAGE..2
(-1150 1525);
FORCEPROP 2 LAST $XR1 236 
J 0
(-841 1525);
DISPLAY 0.638298 (-841 1525);
PAINT MONO (-841 1525);
FORCEPROP 2 LAST $XR0 253 
J 0
(-961 1525);
DISPLAY 0.638298 (-961 1525);
PAINT MONO (-961 1525);
FORCEPROP 2 LAST CDS_LIB standard
J 0
(-1150 1525);
PAINT MONO (-1150 1525);
DISPLAY INVISIBLE (-1150 1525);
FORCEPROP 1 LAST OFFPAGE TRUE
J 0
(-825 1400);
DISPLAY 0.872340 (-825 1400);
PAINT GREEN (-825 1400);
DISPLAY INVISIBLE (-825 1400);
FORCEPROP 1 LAST COMMENT_BODY TRUE
J 0
(-1195 1430);
DISPLAY 0.872340 (-1195 1430);
PAINT GREEN (-1195 1430);
DISPLAY INVISIBLE (-1195 1430);
FORCEPROP 2 LAST PATH I55
J 0
(-825 1575);
DISPLAY 0.680851 (-825 1575);
DISPLAY INVISIBLE (-825 1575);
FORCEADD OFFPAGE..2
(-1175 1325);
FORCEPROP 2 LAST $XR1 253 
J 0
(-866 1325);
DISPLAY 0.638298 (-866 1325);
PAINT MONO (-866 1325);
FORCEPROP 2 LAST $XR0 150 
J 0
(-986 1325);
DISPLAY 0.638298 (-986 1325);
PAINT MONO (-986 1325);
FORCEPROP 2 LAST CDS_LIB standard
J 0
(-1175 1325);
PAINT MONO (-1175 1325);
DISPLAY INVISIBLE (-1175 1325);
FORCEPROP 1 LAST OFFPAGE TRUE
J 0
(-850 1200);
DISPLAY 0.872340 (-850 1200);
PAINT GREEN (-850 1200);
DISPLAY INVISIBLE (-850 1200);
FORCEPROP 1 LAST COMMENT_BODY TRUE
J 0
(-1220 1230);
DISPLAY 0.872340 (-1220 1230);
PAINT GREEN (-1220 1230);
DISPLAY INVISIBLE (-1220 1230);
FORCEPROP 2 LAST PATH I56
J 0
(-1000 1400);
DISPLAY 0.680851 (-1000 1400);
DISPLAY INVISIBLE (-1000 1400);
FORCEADD OFFPAGE..2
(-1150 1575);
FORCEPROP 2 LAST $XR1 253 
J 0
(-841 1575);
DISPLAY 0.638298 (-841 1575);
PAINT MONO (-841 1575);
FORCEPROP 2 LAST $XR0 236 
J 0
(-961 1575);
DISPLAY 0.638298 (-961 1575);
PAINT MONO (-961 1575);
FORCEPROP 2 LAST CDS_LIB standard
J 0
(-1150 1575);
PAINT MONO (-1150 1575);
DISPLAY INVISIBLE (-1150 1575);
FORCEPROP 1 LAST OFFPAGE TRUE
J 0
(-825 1450);
DISPLAY 0.872340 (-825 1450);
PAINT GREEN (-825 1450);
DISPLAY INVISIBLE (-825 1450);
FORCEPROP 1 LAST COMMENT_BODY TRUE
J 0
(-1195 1480);
DISPLAY 0.872340 (-1195 1480);
PAINT GREEN (-1195 1480);
DISPLAY INVISIBLE (-1195 1480);
FORCEPROP 2 LAST PATH I57
J 0
(-825 1625);
DISPLAY 0.680851 (-825 1625);
DISPLAY INVISIBLE (-825 1625);
FORCEADD OFFPAGE..2
(-1150 1825);
FORCEPROP 2 LAST $XR1 236 
J 0
(-841 1825);
DISPLAY 0.638298 (-841 1825);
PAINT MONO (-841 1825);
FORCEPROP 2 LAST $XR0 253 
J 0
(-961 1825);
DISPLAY 0.638298 (-961 1825);
PAINT MONO (-961 1825);
FORCEPROP 2 LAST CDS_LIB standard
J 0
(-1150 1825);
PAINT MONO (-1150 1825);
DISPLAY INVISIBLE (-1150 1825);
FORCEPROP 1 LAST OFFPAGE TRUE
J 0
(-825 1700);
DISPLAY 0.872340 (-825 1700);
PAINT GREEN (-825 1700);
DISPLAY INVISIBLE (-825 1700);
FORCEPROP 1 LAST COMMENT_BODY TRUE
J 0
(-1195 1730);
DISPLAY 0.872340 (-1195 1730);
PAINT GREEN (-1195 1730);
DISPLAY INVISIBLE (-1195 1730);
FORCEPROP 2 LAST PATH I58
J 0
(-825 1875);
DISPLAY 0.680851 (-825 1875);
DISPLAY INVISIBLE (-825 1875);
FORCEADD OFFPAGE..2
(-1150 1875);
FORCEPROP 2 LAST $XR1 253 
J 0
(-841 1875);
DISPLAY 0.638298 (-841 1875);
PAINT MONO (-841 1875);
FORCEPROP 2 LAST $XR0 236 
J 0
(-961 1875);
DISPLAY 0.638298 (-961 1875);
PAINT MONO (-961 1875);
FORCEPROP 2 LAST CDS_LIB standard
J 0
(-1150 1875);
PAINT MONO (-1150 1875);
DISPLAY INVISIBLE (-1150 1875);
FORCEPROP 1 LAST OFFPAGE TRUE
J 0
(-825 1750);
DISPLAY 0.872340 (-825 1750);
PAINT GREEN (-825 1750);
DISPLAY INVISIBLE (-825 1750);
FORCEPROP 1 LAST COMMENT_BODY TRUE
J 0
(-1195 1780);
DISPLAY 0.872340 (-1195 1780);
PAINT GREEN (-1195 1780);
DISPLAY INVISIBLE (-1195 1780);
FORCEPROP 2 LAST PATH I59
J 0
(-825 1925);
DISPLAY 0.680851 (-825 1925);
DISPLAY INVISIBLE (-825 1925);
FORCEADD Q_RES..2
(-6025 2200);
FORCEPROP 1 LAST LOCATION R3709
J 0
(-5980 2325);
DISPLAY 0.978723 (-5980 2325);
FORCEPROP 2 LAST $SEC 1
J 0
(-5975 2425);
DISPLAY 0.680851 (-5975 2425);
PAINT MONO (-5975 2425);
DISPLAY INVISIBLE (-5975 2425);
FORCEPROP 2 LAST CDS_SEC 1
J 0
(-5975 2425);
DISPLAY 1.021277 (-5975 2425);
DISPLAY INVISIBLE (-5975 2425);
FORCEPROP 1 LASTPIN (-6025 2300) $PN 1
J 0
(-6020 2262);
DISPLAY 0.787234 (-6020 2262);
FORCEPROP 1 LASTPIN (-6025 2100) $PN 2
J 0
(-6020 2110);
DISPLAY 0.787234 (-6020 2110);
FORCEPROP 1 LAST PACK_TYPE 0402LF
J 0
(-5985 2025);
DISPLAY 0.638298 (-5985 2025);
FORCEPROP 1 LAST TOLERANCE 1%
J 0
(-5980 2225);
DISPLAY 0.638298 (-5980 2225);
FORCEPROP 1 LAST VALUE 1K
J 0
(-5980 2275);
DISPLAY 0.638298 (-5980 2275);
FORCEPROP 1 LAST MATERIAL CHIP
J 0
(-5985 2125);
DISPLAY 0.638298 (-5985 2125);
FORCEPROP 1 LAST WATTAGE 1/16W
J 0
(-5985 2175);
DISPLAY 0.638298 (-5985 2175);
FORCEPROP 2 LAST CDS_LIB pure_quanta
J 0
(-6025 2200);
PAINT MONO (-6025 2200);
DISPLAY INVISIBLE (-6025 2200);
FORCEPROP 1 LAST PATH I6
J 0
(-5975 2375);
DISPLAY 0.978723 (-5975 2375);
PAINT WHITE (-5975 2375);
DISPLAY INVISIBLE (-5975 2375);
FORCEPROP 1 LAST PART_NUMBER CS21002FB06
J 0
(-5985 2075);
DISPLAY 0.510638 (-5985 2075);
DISPLAY INVISIBLE (-5985 2075);
FORCEADD OFFPAGE..2
(-1175 2125);
FORCEPROP 2 LAST $XR1 236 
J 0
(-866 2125);
DISPLAY 0.638298 (-866 2125);
PAINT MONO (-866 2125);
FORCEPROP 2 LAST $XR0 253 
J 0
(-986 2125);
DISPLAY 0.638298 (-986 2125);
PAINT MONO (-986 2125);
FORCEPROP 2 LAST CDS_LIB standard
J 0
(-1175 2125);
PAINT MONO (-1175 2125);
DISPLAY INVISIBLE (-1175 2125);
FORCEPROP 1 LAST OFFPAGE TRUE
J 0
(-850 2000);
DISPLAY 0.872340 (-850 2000);
PAINT GREEN (-850 2000);
DISPLAY INVISIBLE (-850 2000);
FORCEPROP 1 LAST COMMENT_BODY TRUE
J 0
(-1220 2030);
DISPLAY 0.872340 (-1220 2030);
PAINT GREEN (-1220 2030);
DISPLAY INVISIBLE (-1220 2030);
FORCEPROP 2 LAST PATH I60
J 0
(-850 2175);
DISPLAY 0.680851 (-850 2175);
DISPLAY INVISIBLE (-850 2175);
FORCEADD OFFPAGE..2
(-1175 2175);
FORCEPROP 2 LAST $XR1 253 
J 0
(-866 2175);
DISPLAY 0.638298 (-866 2175);
PAINT MONO (-866 2175);
FORCEPROP 2 LAST $XR0 236 
J 0
(-986 2175);
DISPLAY 0.638298 (-986 2175);
PAINT MONO (-986 2175);
FORCEPROP 2 LAST CDS_LIB standard
J 0
(-1175 2175);
PAINT MONO (-1175 2175);
DISPLAY INVISIBLE (-1175 2175);
FORCEPROP 1 LAST OFFPAGE TRUE
J 0
(-850 2050);
DISPLAY 0.872340 (-850 2050);
PAINT GREEN (-850 2050);
DISPLAY INVISIBLE (-850 2050);
FORCEPROP 1 LAST COMMENT_BODY TRUE
J 0
(-1220 2080);
DISPLAY 0.872340 (-1220 2080);
PAINT GREEN (-1220 2080);
DISPLAY INVISIBLE (-1220 2080);
FORCEPROP 2 LAST PATH I61
J 0
(-850 2225);
DISPLAY 0.680851 (-850 2225);
DISPLAY INVISIBLE (-850 2225);
FORCEADD OFFPAGE..2
(-1175 2400);
FORCEPROP 2 LAST $XR2 236 
J 0
(-746 2400);
DISPLAY 0.638298 (-746 2400);
PAINT MONO (-746 2400);
FORCEPROP 2 LAST $XR1 272 
J 0
(-866 2400);
DISPLAY 0.638298 (-866 2400);
PAINT MONO (-866 2400);
FORCEPROP 2 LAST $XR0 253 
J 0
(-986 2400);
DISPLAY 0.638298 (-986 2400);
PAINT MONO (-986 2400);
FORCEPROP 2 LAST CDS_LIB standard
J 0
(-1175 2400);
PAINT MONO (-1175 2400);
DISPLAY INVISIBLE (-1175 2400);
FORCEPROP 1 LAST OFFPAGE TRUE
J 0
(-850 2275);
DISPLAY 0.872340 (-850 2275);
PAINT GREEN (-850 2275);
DISPLAY INVISIBLE (-850 2275);
FORCEPROP 1 LAST COMMENT_BODY TRUE
J 0
(-1220 2305);
DISPLAY 0.872340 (-1220 2305);
PAINT GREEN (-1220 2305);
DISPLAY INVISIBLE (-1220 2305);
FORCEPROP 2 LAST PATH I62
J 0
(-850 2450);
DISPLAY 0.680851 (-850 2450);
DISPLAY INVISIBLE (-850 2450);
FORCEADD OFFPAGE..2
(-1175 2450);
FORCEPROP 2 LAST $XR2 272 
J 0
(-746 2450);
DISPLAY 0.638298 (-746 2450);
PAINT MONO (-746 2450);
FORCEPROP 2 LAST $XR1 253 
J 0
(-866 2450);
DISPLAY 0.638298 (-866 2450);
PAINT MONO (-866 2450);
FORCEPROP 2 LAST $XR0 236 
J 0
(-986 2450);
DISPLAY 0.638298 (-986 2450);
PAINT MONO (-986 2450);
FORCEPROP 2 LAST CDS_LIB standard
J 0
(-1175 2450);
PAINT MONO (-1175 2450);
DISPLAY INVISIBLE (-1175 2450);
FORCEPROP 1 LAST OFFPAGE TRUE
J 0
(-850 2325);
DISPLAY 0.872340 (-850 2325);
PAINT GREEN (-850 2325);
DISPLAY INVISIBLE (-850 2325);
FORCEPROP 1 LAST COMMENT_BODY TRUE
J 0
(-1220 2355);
DISPLAY 0.872340 (-1220 2355);
PAINT GREEN (-1220 2355);
DISPLAY INVISIBLE (-1220 2355);
FORCEPROP 2 LAST PATH I63
J 0
(-850 2500);
DISPLAY 0.680851 (-850 2500);
DISPLAY INVISIBLE (-850 2500);
FORCEADD OFFPAGE..2
(-1175 2775);
FORCEPROP 2 LAST $XR1 253 
J 0
(-866 2775);
DISPLAY 0.638298 (-866 2775);
PAINT MONO (-866 2775);
FORCEPROP 2 LAST $XR0 151 
J 0
(-986 2775);
DISPLAY 0.638298 (-986 2775);
PAINT MONO (-986 2775);
FORCEPROP 2 LAST CDS_LIB standard
J 0
(-1175 2775);
PAINT MONO (-1175 2775);
DISPLAY INVISIBLE (-1175 2775);
FORCEPROP 1 LAST OFFPAGE TRUE
J 0
(-850 2650);
DISPLAY 0.872340 (-850 2650);
PAINT GREEN (-850 2650);
DISPLAY INVISIBLE (-850 2650);
FORCEPROP 1 LAST COMMENT_BODY TRUE
J 0
(-1220 2680);
DISPLAY 0.872340 (-1220 2680);
PAINT GREEN (-1220 2680);
DISPLAY INVISIBLE (-1220 2680);
FORCEPROP 2 LAST PATH I64
J 0
(-850 2825);
DISPLAY 0.680851 (-850 2825);
DISPLAY INVISIBLE (-850 2825);
FORCEADD OFFPAGE..2
(-1175 2825);
FORCEPROP 2 LAST $XR1 151 
J 0
(-866 2825);
DISPLAY 0.638298 (-866 2825);
PAINT MONO (-866 2825);
FORCEPROP 2 LAST $XR0 253 
J 0
(-986 2825);
DISPLAY 0.638298 (-986 2825);
PAINT MONO (-986 2825);
FORCEPROP 2 LAST CDS_LIB standard
J 0
(-1175 2825);
PAINT MONO (-1175 2825);
DISPLAY INVISIBLE (-1175 2825);
FORCEPROP 1 LAST OFFPAGE TRUE
J 0
(-850 2700);
DISPLAY 0.872340 (-850 2700);
PAINT GREEN (-850 2700);
DISPLAY INVISIBLE (-850 2700);
FORCEPROP 1 LAST COMMENT_BODY TRUE
J 0
(-1220 2730);
DISPLAY 0.872340 (-1220 2730);
PAINT GREEN (-1220 2730);
DISPLAY INVISIBLE (-1220 2730);
FORCEPROP 2 LAST PATH I65
J 0
(-850 2875);
DISPLAY 0.680851 (-850 2875);
DISPLAY INVISIBLE (-850 2875);
FORCEADD Q_RES..1
(-2950 4300);
FORCEPROP 1 LAST LOCATION R3722
J 0
(-3175 4300);
DISPLAY 0.510638 (-3175 4300);
FORCEPROP 0 LAST $SEC 1
J 0
(-3175 4350);
DISPLAY INVISIBLE (-3175 4350);
FORCEPROP 0 LAST CDS_SEC 1
J 0
(-3175 4350);
DISPLAY INVISIBLE (-3175 4350);
FORCEPROP 1 LASTPIN (-3050 4300) $PN 1
J 0
(-3038 4312);
DISPLAY 0.787234 (-3038 4312);
PAINT MONO (-3038 4312);
DISPLAY INVISIBLE (-3038 4312);
FORCEPROP 1 LASTPIN (-2850 4300) $PN 2
J 0
(-2888 4312);
DISPLAY 0.787234 (-2888 4312);
PAINT MONO (-2888 4312);
DISPLAY INVISIBLE (-2888 4312);
FORCEPROP 1 LAST TOLERANCE 5%
J 0
(-2775 4300);
DISPLAY 0.510638 (-2775 4300);
FORCEPROP 1 LAST MATERIAL CHIP
J 0
(-2700 4300);
DISPLAY 0.510638 (-2700 4300);
FORCEPROP 1 LAST VALUE 0
J 2
(-2800 4300);
DISPLAY 0.510638 (-2800 4300);
FORCEPROP 1 LAST WATTAGE 1/16W
J 2
(-2775 4200);
DISPLAY 0.510638 (-2775 4200);
DISPLAY INVISIBLE (-2775 4200);
FORCEPROP 1 LAST PACK_TYPE 0402LF
J 0
(-3050 4200);
DISPLAY 0.510638 (-3050 4200);
DISPLAY INVISIBLE (-3050 4200);
FORCEPROP 2 LAST CDS_LIB pure_quanta
J 0
(-2950 4300);
DISPLAY INVISIBLE (-2950 4300);
FORCEPROP 1 LAST PATH I66
J 0
(-3000 4450);
DISPLAY 0.978723 (-3000 4450);
PAINT WHITE (-3000 4450);
DISPLAY INVISIBLE (-3000 4450);
FORCEPROP 1 LAST PART_NUMBER CS00002JB13
J 0
(-3050 4250);
DISPLAY 0.510638 (-3050 4250);
DISPLAY INVISIBLE (-3050 4250);
FORCEADD Q_RES..1
(-2950 4250);
FORCEPROP 1 LAST LOCATION R3721
J 0
(-3175 4250);
DISPLAY 0.510638 (-3175 4250);
FORCEPROP 0 LAST $SEC 1
J 0
(-3175 4300);
DISPLAY INVISIBLE (-3175 4300);
FORCEPROP 0 LAST CDS_SEC 1
J 0
(-3175 4300);
DISPLAY INVISIBLE (-3175 4300);
FORCEPROP 1 LASTPIN (-3050 4250) $PN 1
J 0
(-3038 4262);
DISPLAY 0.787234 (-3038 4262);
PAINT MONO (-3038 4262);
DISPLAY INVISIBLE (-3038 4262);
FORCEPROP 1 LASTPIN (-2850 4250) $PN 2
J 0
(-2888 4262);
DISPLAY 0.787234 (-2888 4262);
PAINT MONO (-2888 4262);
DISPLAY INVISIBLE (-2888 4262);
FORCEPROP 1 LAST MATERIAL CHIP
J 0
(-2700 4250);
DISPLAY 0.510638 (-2700 4250);
FORCEPROP 1 LAST TOLERANCE 5%
J 0
(-2775 4250);
DISPLAY 0.510638 (-2775 4250);
FORCEPROP 1 LAST VALUE 0
J 2
(-2800 4250);
DISPLAY 0.510638 (-2800 4250);
FORCEPROP 2 LAST CDS_LIB pure_quanta
J 0
(-2950 4250);
DISPLAY INVISIBLE (-2950 4250);
FORCEPROP 1 LAST WATTAGE 1/16W
J 2
(-2850 4175);
DISPLAY 0.319149 (-2850 4175);
DISPLAY INVISIBLE (-2850 4175);
FORCEPROP 1 LAST PACK_TYPE 0402LF
J 0
(-2700 4250);
DISPLAY 0.510638 (-2700 4250);
DISPLAY INVISIBLE (-2700 4250);
FORCEPROP 1 LAST PATH I67
J 0
(-3000 4400);
DISPLAY 0.978723 (-3000 4400);
PAINT WHITE (-3000 4400);
DISPLAY INVISIBLE (-3000 4400);
FORCEPROP 1 LAST PART_NUMBER CS00002JB13
J 0
(-3025 4200);
DISPLAY 0.319149 (-3025 4200);
DISPLAY INVISIBLE (-3025 4200);
FORCEADD Q_RES..1
R 2
(-2825 4550);
FORCEPROP 1 LAST LOCATION R3712
J 2
(-2650 4550);
DISPLAY 0.510638 (-2650 4550);
FORCEPROP 2 LAST $SEC 1
J 2
(-2775 4750);
DISPLAY 0.680851 (-2775 4750);
PAINT MONO (-2775 4750);
DISPLAY INVISIBLE (-2775 4750);
FORCEPROP 2 LAST CDS_SEC 1
J 2
(-2775 4750);
DISPLAY 1.021277 (-2775 4750);
DISPLAY INVISIBLE (-2775 4750);
FORCEPROP 1 LASTPIN (-2725 4550) $PN 1
J 2
(-2737 4562);
DISPLAY 0.787234 (-2737 4562);
FORCEPROP 1 LASTPIN (-2925 4550) $PN 2
J 2
(-2887 4562);
DISPLAY 0.787234 (-2887 4562);
FORCEPROP 1 LAST MATERIAL CHIP
J 2
(-3125 4550);
DISPLAY 0.404255 (-3125 4550);
FORCEPROP 1 LAST TOLERANCE 1%
J 2
(-3050 4550);
DISPLAY 0.404255 (-3050 4550);
FORCEPROP 1 LAST VALUE 33.2
J 0
(-3025 4550);
DISPLAY 0.404255 (-3025 4550);
FORCEPROP 1 LAST PACK_TYPE 0402LF
J 2
(-3075 4550);
DISPLAY 0.404255 (-3075 4550);
DISPLAY INVISIBLE (-3075 4550);
FORCEPROP 2 LAST CDS_LIB pure_quanta
J 2
(-2825 4550);
PAINT MONO (-2825 4550);
DISPLAY INVISIBLE (-2825 4550);
FORCEPROP 1 LAST WATTAGE 1/16W
J 0
(-2925 4475);
DISPLAY 0.319149 (-2925 4475);
DISPLAY INVISIBLE (-2925 4475);
FORCEPROP 1 LAST PATH I68
J 2
(-2775 4700);
DISPLAY 0.978723 (-2775 4700);
PAINT WHITE (-2775 4700);
DISPLAY INVISIBLE (-2775 4700);
FORCEPROP 1 LAST PART_NUMBER CS03322FB03
J 2
(-2750 4500);
DISPLAY 0.319149 (-2750 4500);
DISPLAY INVISIBLE (-2750 4500);
FORCEADD Q_RES..1
R 2
(-2825 4500);
FORCEPROP 1 LAST LOCATION R3711
J 2
(-2650 4500);
DISPLAY 0.510638 (-2650 4500);
FORCEPROP 2 LAST $SEC 1
J 2
(-2775 4700);
DISPLAY 0.680851 (-2775 4700);
PAINT MONO (-2775 4700);
DISPLAY INVISIBLE (-2775 4700);
FORCEPROP 2 LAST CDS_SEC 1
J 2
(-2775 4700);
DISPLAY 1.021277 (-2775 4700);
DISPLAY INVISIBLE (-2775 4700);
FORCEPROP 1 LASTPIN (-2725 4500) $PN 1
J 2
(-2737 4512);
DISPLAY 0.787234 (-2737 4512);
FORCEPROP 1 LASTPIN (-2925 4500) $PN 2
J 2
(-2887 4512);
DISPLAY 0.787234 (-2887 4512);
FORCEPROP 1 LAST WATTAGE 1/16W
J 0
(-2950 4675);
DISPLAY 0.404255 (-2950 4675);
FORCEPROP 1 LAST MATERIAL CHIP
J 2
(-3125 4500);
DISPLAY 0.404255 (-3125 4500);
FORCEPROP 1 LAST TOLERANCE 1%
J 2
(-3050 4500);
DISPLAY 0.404255 (-3050 4500);
FORCEPROP 1 LAST VALUE 33.2
J 0
(-3025 4500);
DISPLAY 0.404255 (-3025 4500);
FORCEPROP 1 LAST PACK_TYPE 0402LF
J 2
(-2725 4675);
DISPLAY 0.404255 (-2725 4675);
FORCEPROP 2 LAST CDS_LIB pure_quanta
J 2
(-2825 4500);
PAINT MONO (-2825 4500);
DISPLAY INVISIBLE (-2825 4500);
FORCEPROP 1 LAST PATH I69
J 2
(-2775 4650);
DISPLAY 0.978723 (-2775 4650);
PAINT WHITE (-2775 4650);
DISPLAY INVISIBLE (-2775 4650);
FORCEPROP 1 LAST PART_NUMBER CS03322FB03
J 2
(-2725 4625);
DISPLAY 0.404255 (-2725 4625);
DISPLAY INVISIBLE (-2725 4625);
FORCEADD Q_RES..2
(-6575 2850);
FORCEPROP 1 LAST LOCATION R3703
J 0
(-6530 2975);
DISPLAY 0.978723 (-6530 2975);
FORCEPROP 2 LAST $SEC 1
J 0
(-6525 3075);
DISPLAY 0.680851 (-6525 3075);
PAINT MONO (-6525 3075);
DISPLAY INVISIBLE (-6525 3075);
FORCEPROP 2 LAST CDS_SEC 1
J 0
(-6525 3075);
DISPLAY 1.021277 (-6525 3075);
DISPLAY INVISIBLE (-6525 3075);
FORCEPROP 1 LASTPIN (-6575 2950) $PN 1
J 0
(-6570 2912);
DISPLAY 0.787234 (-6570 2912);
FORCEPROP 1 LASTPIN (-6575 2750) $PN 2
J 0
(-6570 2760);
DISPLAY 0.787234 (-6570 2760);
FORCEPROP 1 LAST WATTAGE 1/16W
J 0
(-6535 2825);
DISPLAY 0.638298 (-6535 2825);
FORCEPROP 1 LAST VALUE 10K
J 0
(-6530 2925);
DISPLAY 0.638298 (-6530 2925);
FORCEPROP 1 LAST PACK_TYPE 0402LF
J 0
(-6535 2725);
DISPLAY 0.638298 (-6535 2725);
FORCEPROP 1 LAST TOLERANCE 1%
J 0
(-6530 2875);
DISPLAY 0.638298 (-6530 2875);
FORCEPROP 1 LAST MATERIAL EMPTY
J 0
(-6535 2775);
DISPLAY 0.638298 (-6535 2775);
PAINT RED (-6535 2775);
FORCEPROP 2 LAST CDS_LIB pure_quanta
J 0
(-6575 2850);
PAINT MONO (-6575 2850);
DISPLAY INVISIBLE (-6575 2850);
FORCEPROP 1 LAST PATH I7
J 0
(-6525 3025);
DISPLAY 0.978723 (-6525 3025);
PAINT WHITE (-6525 3025);
DISPLAY INVISIBLE (-6525 3025);
FORCEPROP 1 LAST PART_NUMBER CS31002FB08
J 0
(-6535 2725);
DISPLAY 0.510638 (-6535 2725);
DISPLAY INVISIBLE (-6535 2725);
FORCEADD OFFPAGE..5
R 2
(-1750 4250);
FORCEPROP 2 LAST $XR1 253 
J 0
(-1441 4250);
DISPLAY 0.638298 (-1441 4250);
PAINT MONO (-1441 4250);
FORCEPROP 2 LAST $XR0 236 
J 0
(-1561 4250);
DISPLAY 0.638298 (-1561 4250);
PAINT MONO (-1561 4250);
FORCEPROP 2 LAST CDS_LIB standard
J 0
(-1750 4250);
DISPLAY INVISIBLE (-1750 4250);
FORCEPROP 1 LAST OFFPAGE TRUE
J 2
(-2075 4125);
DISPLAY 0.872340 (-2075 4125);
DISPLAY INVISIBLE (-2075 4125);
FORCEPROP 1 LAST COMMENT_BODY TRUE
J 2
(-1850 4175);
DISPLAY 0.872340 (-1850 4175);
PAINT GREEN (-1850 4175);
DISPLAY INVISIBLE (-1850 4175);
FORCEPROP 2 LAST PATH I70
J 0
(-1425 4300);
DISPLAY 0.680851 (-1425 4300);
DISPLAY INVISIBLE (-1425 4300);
FORCEADD OFFPAGE..3
(-1750 4300);
FORCEPROP 2 LAST $XR1 236 
J 0
(-1416 4300);
DISPLAY 0.638298 (-1416 4300);
PAINT MONO (-1416 4300);
FORCEPROP 2 LAST $XR0 253 
J 0
(-1536 4300);
DISPLAY 0.638298 (-1536 4300);
PAINT MONO (-1536 4300);
FORCEPROP 2 LAST CDS_LIB standard
J 0
(-1750 4300);
DISPLAY INVISIBLE (-1750 4300);
FORCEPROP 1 LAST OFFPAGE TRUE
J 0
(-1425 4175);
DISPLAY 0.872340 (-1425 4175);
DISPLAY INVISIBLE (-1425 4175);
FORCEPROP 1 LAST COMMENT_BODY TRUE
J 0
(-1800 4200);
DISPLAY 0.872340 (-1800 4200);
PAINT GREEN (-1800 4200);
DISPLAY INVISIBLE (-1800 4200);
FORCEPROP 2 LAST PATH I71
J 0
(-1400 4350);
DISPLAY 0.680851 (-1400 4350);
DISPLAY INVISIBLE (-1400 4350);
FORCEADD OFFPAGE..4
(-1775 4550);
FORCEPROP 2 LAST $XR1 253 
J 0
(-1469 4550);
DISPLAY 0.638298 (-1469 4550);
PAINT MONO (-1469 4550);
FORCEPROP 2 LAST $XR0 150 
J 0
(-1589 4550);
DISPLAY 0.638298 (-1589 4550);
PAINT MONO (-1589 4550);
FORCEPROP 2 LAST CDS_LIB standard
J 0
(-1775 4550);
DISPLAY INVISIBLE (-1775 4550);
FORCEPROP 1 LAST OFFPAGE TRUE
J 0
(-1450 4425);
DISPLAY 0.872340 (-1450 4425);
DISPLAY INVISIBLE (-1450 4425);
FORCEPROP 1 LAST COMMENT_BODY TRUE
J 0
(-1800 4450);
DISPLAY 0.872340 (-1800 4450);
PAINT GREEN (-1800 4450);
DISPLAY INVISIBLE (-1800 4450);
FORCEPROP 2 LAST PATH I72
J 0
(-1600 4625);
DISPLAY 0.680851 (-1600 4625);
DISPLAY INVISIBLE (-1600 4625);
FORCEADD OFFPAGE..3
(-1775 4500);
FORCEPROP 2 LAST $XR1 253 
J 0
(-1441 4500);
DISPLAY 0.638298 (-1441 4500);
PAINT MONO (-1441 4500);
FORCEPROP 2 LAST $XR0 150 
J 0
(-1561 4500);
DISPLAY 0.638298 (-1561 4500);
PAINT MONO (-1561 4500);
FORCEPROP 2 LAST CDS_LIB standard
J 0
(-1775 4500);
DISPLAY INVISIBLE (-1775 4500);
FORCEPROP 1 LAST OFFPAGE TRUE
J 0
(-1450 4375);
DISPLAY 0.872340 (-1450 4375);
PAINT GREEN (-1450 4375);
DISPLAY INVISIBLE (-1450 4375);
FORCEPROP 1 LAST COMMENT_BODY TRUE
J 0
(-1825 4400);
DISPLAY 0.872340 (-1825 4400);
PAINT GREEN (-1825 4400);
DISPLAY INVISIBLE (-1825 4400);
FORCEPROP 2 LAST PATH I73
J 0
(-1575 4575);
DISPLAY 0.680851 (-1575 4575);
DISPLAY INVISIBLE (-1575 4575);
FORCEADD TCA9548APWR..1
(-4275 4275);
FORCEPROP 1 LAST LOCATION U39
J 0
(-4475 4855);
DISPLAY 0.723404 (-4475 4855);
PAINT GREEN (-4475 4855);
FORCEPROP 2 LAST SEC 1
J 0
(-4475 5000);
DISPLAY 0.680851 (-4475 5000);
PAINT MONO (-4475 5000);
DISPLAY INVISIBLE (-4475 5000);
FORCEPROP 2 LASTPIN (-4625 4600) $PN 1
J 2
(-4635 4610);
DISPLAY 0.680851 (-4635 4610);
PAINT MONO (-4635 4610);
FORCEPROP 2 LASTPIN (-4625 4550) $PN 2
J 2
(-4635 4560);
DISPLAY 0.680851 (-4635 4560);
PAINT MONO (-4635 4560);
FORCEPROP 2 LASTPIN (-4625 4500) $PN 21
J 2
(-4635 4510);
DISPLAY 0.680851 (-4635 4510);
PAINT MONO (-4635 4510);
FORCEPROP 2 LASTPIN (-3925 3850) $PN 12
J 0
(-3915 3860);
DISPLAY 0.680851 (-3915 3860);
PAINT MONO (-3915 3860);
FORCEPROP 2 LASTPIN (-4625 4400) $PN 3
J 2
(-4635 4410);
DISPLAY 0.680851 (-4635 4410);
PAINT MONO (-4635 4410);
FORCEPROP 2 LASTPIN (-4625 4250) $PN 5
J 2
(-4635 4260);
DISPLAY 0.680851 (-4635 4260);
PAINT MONO (-4635 4260);
FORCEPROP 2 LASTPIN (-4625 4150) $PN 7
J 2
(-4635 4160);
DISPLAY 0.680851 (-4635 4160);
PAINT MONO (-4635 4160);
FORCEPROP 2 LASTPIN (-4625 4050) $PN 9
J 2
(-4635 4060);
DISPLAY 0.680851 (-4635 4060);
PAINT MONO (-4635 4060);
FORCEPROP 2 LASTPIN (-4625 3950) $PN 11
J 2
(-4635 3960);
DISPLAY 0.680851 (-4635 3960);
PAINT MONO (-4635 3960);
FORCEPROP 2 LASTPIN (-3925 4250) $PN 14
J 0
(-3915 4260);
DISPLAY 0.680851 (-3915 4260);
PAINT MONO (-3915 4260);
FORCEPROP 2 LASTPIN (-3925 4150) $PN 16
J 0
(-3915 4160);
DISPLAY 0.680851 (-3915 4160);
PAINT MONO (-3915 4160);
FORCEPROP 2 LASTPIN (-3925 4050) $PN 18
J 0
(-3915 4060);
DISPLAY 0.680851 (-3915 4060);
PAINT MONO (-3915 4060);
FORCEPROP 2 LASTPIN (-3925 3950) $PN 20
J 0
(-3915 3960);
DISPLAY 0.680851 (-3915 3960);
PAINT MONO (-3915 3960);
FORCEPROP 2 LASTPIN (-3925 4500) $PN 22
J 0
(-3915 4510);
DISPLAY 0.680851 (-3915 4510);
PAINT MONO (-3915 4510);
FORCEPROP 2 LASTPIN (-4625 4300) $PN 4
J 2
(-4635 4310);
DISPLAY 0.680851 (-4635 4310);
PAINT MONO (-4635 4310);
FORCEPROP 2 LASTPIN (-4625 4200) $PN 6
J 2
(-4635 4210);
DISPLAY 0.680851 (-4635 4210);
PAINT MONO (-4635 4210);
FORCEPROP 2 LASTPIN (-4625 4100) $PN 8
J 2
(-4635 4110);
DISPLAY 0.680851 (-4635 4110);
PAINT MONO (-4635 4110);
FORCEPROP 2 LASTPIN (-4625 4000) $PN 10
J 2
(-4635 4010);
DISPLAY 0.680851 (-4635 4010);
PAINT MONO (-4635 4010);
FORCEPROP 2 LASTPIN (-3925 4300) $PN 13
J 0
(-3915 4310);
DISPLAY 0.680851 (-3915 4310);
PAINT MONO (-3915 4310);
FORCEPROP 2 LASTPIN (-3925 4200) $PN 15
J 0
(-3915 4210);
DISPLAY 0.680851 (-3915 4210);
PAINT MONO (-3915 4210);
FORCEPROP 2 LASTPIN (-3925 4100) $PN 17
J 0
(-3915 4110);
DISPLAY 0.680851 (-3915 4110);
PAINT MONO (-3915 4110);
FORCEPROP 2 LASTPIN (-3925 4000) $PN 19
J 0
(-3915 4010);
DISPLAY 0.680851 (-3915 4010);
PAINT MONO (-3915 4010);
FORCEPROP 2 LASTPIN (-3925 4550) $PN 23
J 0
(-3915 4560);
DISPLAY 0.680851 (-3915 4560);
PAINT MONO (-3915 4560);
FORCEPROP 2 LASTPIN (-4625 4700) $PN 24
J 2
(-4635 4710);
DISPLAY 0.680851 (-4635 4710);
PAINT MONO (-4635 4710);
FORCEPROP 1 LAST MATERIAL IC
J 0
(-4475 4755);
DISPLAY 0.723404 (-4475 4755);
PAINT GREEN (-4475 4755);
FORCEPROP 2 LAST PART_TYPE SMLF
J 0
(-4475 4950);
DISPLAY 1.021277 (-4475 4950);
FORCEPROP 2 LAST VALUE TCA9548APWR
J 0
(-4475 4900);
DISPLAY 1.021277 (-4475 4900);
FORCEPROP 2 LAST CDS_LIB pure_quanta
J 0
(-4275 4275);
DISPLAY INVISIBLE (-4275 4275);
FORCEPROP 1 LAST CDS_LMAN_SYM_OUTLINE -200,475,200,-475
J 0
(-4275 4275);
DISPLAY 0.468085 (-4275 4275);
PAINT GREEN (-4275 4275);
DISPLAY INVISIBLE (-4275 4275);
FORCEPROP 1 LAST NEEDS_NO_SIZE TRUE
J 0
(-4275 4275);
DISPLAY 0.723404 (-4275 4275);
PAINT GREEN (-4275 4275);
DISPLAY INVISIBLE (-4275 4275);
FORCEPROP 2 LAST SEC_TYPE 
J 0
(-4475 5000);
DISPLAY 1.021277 (-4475 5000);
DISPLAY INVISIBLE (-4475 5000);
FORCEPROP 1 LAST PATH I74
J 0
(-4275 4275);
DISPLAY 0.723404 (-4275 4275);
PAINT GREEN (-4275 4275);
DISPLAY INVISIBLE (-4275 4275);
FORCEPROP 1 LAST PART_NUMBER AL009548K02
J 0
(-4475 4802);
DISPLAY 0.723404 (-4475 4802);
PAINT GREEN (-4475 4802);
DISPLAY INVISIBLE (-4475 4802);
FORCEADD Q_RES..1
(-2950 4200);
FORCEPROP 1 LAST LOCATION R6228
J 0
(-3175 4200);
DISPLAY 0.510638 (-3175 4200);
FORCEPROP 0 LAST $SEC 1
J 0
(-2700 4225);
DISPLAY 0.680851 (-2700 4225);
PAINT MONO (-2700 4225);
DISPLAY INVISIBLE (-2700 4225);
FORCEPROP 0 LAST CDS_SEC 1
J 0
(-2700 4225);
DISPLAY 0.680851 (-2700 4225);
DISPLAY INVISIBLE (-2700 4225);
FORCEPROP 1 LASTPIN (-3050 4200) $PN 1
J 0
(-3038 4212);
DISPLAY 0.787234 (-3038 4212);
PAINT MONO (-3038 4212);
FORCEPROP 1 LASTPIN (-2850 4200) $PN 2
J 0
(-2888 4212);
DISPLAY 0.787234 (-2888 4212);
PAINT MONO (-2888 4212);
FORCEPROP 1 LAST MATERIAL CHIP
J 0
(-2700 4200);
DISPLAY 0.510638 (-2700 4200);
FORCEPROP 1 LAST VALUE 0
J 2
(-2800 4200);
DISPLAY 0.510638 (-2800 4200);
FORCEPROP 1 LAST TOLERANCE 5%
J 0
(-2775 4200);
DISPLAY 0.510638 (-2775 4200);
FORCEPROP 2 LAST CDS_LIB pure_quanta
J 0
(-2950 4200);
DISPLAY INVISIBLE (-2950 4200);
FORCEPROP 1 LAST PACK_TYPE 0402LF
J 0
(-2700 4200);
DISPLAY 0.510638 (-2700 4200);
DISPLAY INVISIBLE (-2700 4200);
FORCEPROP 1 LAST WATTAGE 1/16W
J 2
(-2850 4125);
DISPLAY 0.319149 (-2850 4125);
DISPLAY INVISIBLE (-2850 4125);
FORCEPROP 1 LAST PATH I75
J 0
(-3000 4350);
DISPLAY 0.978723 (-3000 4350);
PAINT WHITE (-3000 4350);
DISPLAY INVISIBLE (-3000 4350);
FORCEPROP 1 LAST PART_NUMBER CS00002JB13
J 0
(-3025 4150);
DISPLAY 0.319149 (-3025 4150);
DISPLAY INVISIBLE (-3025 4150);
FORCEADD Q_RES..1
(-2950 4150);
FORCEPROP 1 LAST LOCATION R6229
J 0
(-3175 4150);
DISPLAY 0.510638 (-3175 4150);
FORCEPROP 0 LAST $SEC 1
J 0
(-2700 4175);
DISPLAY 0.680851 (-2700 4175);
PAINT MONO (-2700 4175);
DISPLAY INVISIBLE (-2700 4175);
FORCEPROP 0 LAST CDS_SEC 1
J 0
(-2700 4175);
DISPLAY 0.680851 (-2700 4175);
DISPLAY INVISIBLE (-2700 4175);
FORCEPROP 1 LASTPIN (-3050 4150) $PN 1
J 0
(-3038 4162);
DISPLAY 0.787234 (-3038 4162);
PAINT MONO (-3038 4162);
FORCEPROP 1 LASTPIN (-2850 4150) $PN 2
J 0
(-2888 4162);
DISPLAY 0.787234 (-2888 4162);
PAINT MONO (-2888 4162);
FORCEPROP 1 LAST TOLERANCE 5%
J 0
(-2775 4150);
DISPLAY 0.510638 (-2775 4150);
FORCEPROP 1 LAST MATERIAL CHIP
J 0
(-2700 4150);
DISPLAY 0.510638 (-2700 4150);
FORCEPROP 1 LAST VALUE 0
J 2
(-2800 4150);
DISPLAY 0.510638 (-2800 4150);
FORCEPROP 2 LAST CDS_LIB pure_quanta
J 0
(-2950 4150);
DISPLAY INVISIBLE (-2950 4150);
FORCEPROP 1 LAST PACK_TYPE 0402LF
J 0
(-2700 4150);
DISPLAY 0.510638 (-2700 4150);
DISPLAY INVISIBLE (-2700 4150);
FORCEPROP 1 LAST WATTAGE 1/16W
J 2
(-2850 4075);
DISPLAY 0.319149 (-2850 4075);
DISPLAY INVISIBLE (-2850 4075);
FORCEPROP 1 LAST PATH I76
J 0
(-3000 4300);
DISPLAY 0.978723 (-3000 4300);
PAINT WHITE (-3000 4300);
DISPLAY INVISIBLE (-3000 4300);
FORCEPROP 1 LAST PART_NUMBER CS00002JB13
J 0
(-3025 4100);
DISPLAY 0.319149 (-3025 4100);
DISPLAY INVISIBLE (-3025 4100);
FORCEADD OFFPAGE..3
(-1750 4200);
FORCEPROP 2 LAST $XR0 268 
J 0
(-1536 4200);
DISPLAY 0.638298 (-1536 4200);
PAINT MONO (-1536 4200);
FORCEPROP 2 LAST CDS_LIB standard
J 0
(-1750 4200);
DISPLAY INVISIBLE (-1750 4200);
FORCEPROP 1 LAST OFFPAGE TRUE
J 0
(-1425 4075);
DISPLAY 0.872340 (-1425 4075);
DISPLAY INVISIBLE (-1425 4075);
FORCEPROP 1 LAST COMMENT_BODY TRUE
J 0
(-1800 4100);
DISPLAY 0.872340 (-1800 4100);
PAINT GREEN (-1800 4100);
DISPLAY INVISIBLE (-1800 4100);
FORCEPROP 2 LAST PATH I77
J 0
(-1550 4275);
DISPLAY 0.680851 (-1550 4275);
DISPLAY INVISIBLE (-1550 4275);
FORCEADD OFFPAGE..5
R 2
(-1750 4150);
FORCEPROP 2 LAST $XR0 268 
J 0
(-1561 4150);
DISPLAY 0.638298 (-1561 4150);
PAINT MONO (-1561 4150);
FORCEPROP 2 LAST CDS_LIB standard
J 0
(-1750 4150);
DISPLAY INVISIBLE (-1750 4150);
FORCEPROP 1 LAST OFFPAGE TRUE
J 2
(-2075 4025);
DISPLAY 0.872340 (-2075 4025);
DISPLAY INVISIBLE (-2075 4025);
FORCEPROP 1 LAST COMMENT_BODY TRUE
J 2
(-1850 4075);
DISPLAY 0.872340 (-1850 4075);
PAINT GREEN (-1850 4075);
DISPLAY INVISIBLE (-1850 4075);
FORCEPROP 2 LAST PATH I78
J 0
(-1575 4225);
DISPLAY 0.680851 (-1575 4225);
DISPLAY INVISIBLE (-1575 4225);
FORCEADD Q_RES..1
(-2950 4100);
FORCEPROP 1 LAST LOCATION R1312
J 0
(-3175 4100);
DISPLAY 0.510638 (-3175 4100);
FORCEPROP 0 LAST $SEC 1
J 0
(-2700 4125);
DISPLAY 0.680851 (-2700 4125);
PAINT MONO (-2700 4125);
DISPLAY INVISIBLE (-2700 4125);
FORCEPROP 0 LAST CDS_SEC 1
J 0
(-2700 4125);
DISPLAY 0.680851 (-2700 4125);
DISPLAY INVISIBLE (-2700 4125);
FORCEPROP 1 LASTPIN (-3050 4100) $PN 1
J 0
(-3038 4112);
DISPLAY 0.787234 (-3038 4112);
PAINT MONO (-3038 4112);
FORCEPROP 1 LASTPIN (-2850 4100) $PN 2
J 0
(-2888 4112);
DISPLAY 0.787234 (-2888 4112);
PAINT MONO (-2888 4112);
FORCEPROP 1 LAST VALUE 0
J 2
(-2800 4100);
DISPLAY 0.510638 (-2800 4100);
FORCEPROP 1 LAST TOLERANCE 5%
J 0
(-2775 4100);
DISPLAY 0.510638 (-2775 4100);
FORCEPROP 1 LAST MATERIAL CHIP
J 0
(-2700 4100);
DISPLAY 0.510638 (-2700 4100);
FORCEPROP 2 LAST CDS_LIB pure_quanta
J 0
(-2950 4100);
DISPLAY INVISIBLE (-2950 4100);
FORCEPROP 1 LAST PACK_TYPE 0402LF
J 0
(-2700 4100);
DISPLAY 0.510638 (-2700 4100);
DISPLAY INVISIBLE (-2700 4100);
FORCEPROP 1 LAST WATTAGE 1/16W
J 2
(-2850 4025);
DISPLAY 0.319149 (-2850 4025);
DISPLAY INVISIBLE (-2850 4025);
FORCEPROP 1 LAST PATH I79
J 0
(-3000 4250);
DISPLAY 0.978723 (-3000 4250);
PAINT WHITE (-3000 4250);
DISPLAY INVISIBLE (-3000 4250);
FORCEPROP 1 LAST PART_NUMBER CS00002JB13
J 0
(-3025 4050);
DISPLAY 0.319149 (-3025 4050);
DISPLAY INVISIBLE (-3025 4050);
FORCEADD Q_RES..2
(-6300 2850);
FORCEPROP 1 LAST LOCATION R3706
J 0
(-6255 2975);
DISPLAY 0.978723 (-6255 2975);
FORCEPROP 2 LAST $SEC 1
J 0
(-6250 3075);
DISPLAY 0.680851 (-6250 3075);
PAINT MONO (-6250 3075);
DISPLAY INVISIBLE (-6250 3075);
FORCEPROP 2 LAST CDS_SEC 1
J 0
(-6250 3075);
DISPLAY 1.021277 (-6250 3075);
DISPLAY INVISIBLE (-6250 3075);
FORCEPROP 1 LASTPIN (-6300 2950) $PN 1
J 0
(-6295 2912);
DISPLAY 0.787234 (-6295 2912);
FORCEPROP 1 LASTPIN (-6300 2750) $PN 2
J 0
(-6295 2760);
DISPLAY 0.787234 (-6295 2760);
FORCEPROP 1 LAST VALUE 10K
J 0
(-6255 2925);
DISPLAY 0.638298 (-6255 2925);
FORCEPROP 1 LAST WATTAGE 1/16W
J 0
(-6260 2825);
DISPLAY 0.638298 (-6260 2825);
FORCEPROP 1 LAST TOLERANCE 1%
J 0
(-6255 2875);
DISPLAY 0.638298 (-6255 2875);
FORCEPROP 1 LAST MATERIAL EMPTY
J 0
(-6260 2775);
DISPLAY 0.638298 (-6260 2775);
PAINT RED (-6260 2775);
FORCEPROP 1 LAST PACK_TYPE 0402LF
J 0
(-6260 2725);
DISPLAY 0.638298 (-6260 2725);
FORCEPROP 2 LAST CDS_LIB pure_quanta
J 0
(-6300 2850);
PAINT MONO (-6300 2850);
DISPLAY INVISIBLE (-6300 2850);
FORCEPROP 1 LAST PATH I8
J 0
(-6250 3025);
DISPLAY 0.978723 (-6250 3025);
PAINT WHITE (-6250 3025);
DISPLAY INVISIBLE (-6250 3025);
FORCEPROP 1 LAST PART_NUMBER CS31002FB08
J 0
(-6260 2725);
DISPLAY 0.510638 (-6260 2725);
DISPLAY INVISIBLE (-6260 2725);
FORCEADD Q_RES..1
(-2950 4050);
FORCEPROP 1 LAST LOCATION R1315
J 0
(-3175 4050);
DISPLAY 0.510638 (-3175 4050);
FORCEPROP 0 LAST $SEC 1
J 0
(-2700 4075);
DISPLAY 0.680851 (-2700 4075);
PAINT MONO (-2700 4075);
DISPLAY INVISIBLE (-2700 4075);
FORCEPROP 0 LAST CDS_SEC 1
J 0
(-2700 4075);
DISPLAY 0.680851 (-2700 4075);
DISPLAY INVISIBLE (-2700 4075);
FORCEPROP 1 LASTPIN (-3050 4050) $PN 1
J 0
(-3038 4062);
DISPLAY 0.787234 (-3038 4062);
PAINT MONO (-3038 4062);
FORCEPROP 1 LASTPIN (-2850 4050) $PN 2
J 0
(-2888 4062);
DISPLAY 0.787234 (-2888 4062);
PAINT MONO (-2888 4062);
FORCEPROP 1 LAST TOLERANCE 5%
J 0
(-2775 4050);
DISPLAY 0.510638 (-2775 4050);
FORCEPROP 1 LAST VALUE 0
J 2
(-2800 4050);
DISPLAY 0.510638 (-2800 4050);
FORCEPROP 1 LAST MATERIAL CHIP
J 0
(-2700 4050);
DISPLAY 0.510638 (-2700 4050);
FORCEPROP 1 LAST WATTAGE 1/16W
J 2
(-2850 3975);
DISPLAY 0.319149 (-2850 3975);
DISPLAY INVISIBLE (-2850 3975);
FORCEPROP 1 LAST PACK_TYPE 0402LF
J 0
(-2700 4050);
DISPLAY 0.510638 (-2700 4050);
DISPLAY INVISIBLE (-2700 4050);
FORCEPROP 2 LAST CDS_LIB pure_quanta
J 0
(-2950 4050);
DISPLAY INVISIBLE (-2950 4050);
FORCEPROP 1 LAST PATH I80
J 0
(-3000 4200);
DISPLAY 0.978723 (-3000 4200);
PAINT WHITE (-3000 4200);
DISPLAY INVISIBLE (-3000 4200);
FORCEPROP 1 LAST PART_NUMBER CS00002JB13
J 0
(-3025 4000);
DISPLAY 0.319149 (-3025 4000);
DISPLAY INVISIBLE (-3025 4000);
FORCEADD OFFPAGE..5
R 2
(-1750 4050);
FORCEPROP 2 LAST $XR1 259 
J 0
(-1441 4050);
DISPLAY 0.638298 (-1441 4050);
PAINT MONO (-1441 4050);
FORCEPROP 2 LAST $XR0 253 
J 0
(-1561 4050);
DISPLAY 0.638298 (-1561 4050);
PAINT MONO (-1561 4050);
FORCEPROP 2 LAST CDS_LIB standard
J 0
(-1750 4050);
DISPLAY INVISIBLE (-1750 4050);
FORCEPROP 1 LAST OFFPAGE TRUE
J 2
(-2075 3925);
DISPLAY 0.872340 (-2075 3925);
DISPLAY INVISIBLE (-2075 3925);
FORCEPROP 1 LAST COMMENT_BODY TRUE
J 2
(-1850 3975);
DISPLAY 0.872340 (-1850 3975);
PAINT GREEN (-1850 3975);
DISPLAY INVISIBLE (-1850 3975);
FORCEPROP 2 LAST PATH I81
J 0
(-1575 4125);
DISPLAY 0.680851 (-1575 4125);
DISPLAY INVISIBLE (-1575 4125);
FORCEADD OFFPAGE..5
R 2
(-1750 4100);
FORCEPROP 2 LAST $XR1 259 
J 0
(-1441 4100);
DISPLAY 0.638298 (-1441 4100);
PAINT MONO (-1441 4100);
FORCEPROP 2 LAST $XR0 253 
J 0
(-1561 4100);
DISPLAY 0.638298 (-1561 4100);
PAINT MONO (-1561 4100);
FORCEPROP 2 LAST CDS_LIB standard
J 0
(-1750 4100);
DISPLAY INVISIBLE (-1750 4100);
FORCEPROP 1 LAST OFFPAGE TRUE
J 2
(-2075 3975);
DISPLAY 0.872340 (-2075 3975);
DISPLAY INVISIBLE (-2075 3975);
FORCEPROP 1 LAST COMMENT_BODY TRUE
J 2
(-1850 4025);
DISPLAY 0.872340 (-1850 4025);
PAINT GREEN (-1850 4025);
DISPLAY INVISIBLE (-1850 4025);
FORCEPROP 2 LAST PATH I82
J 0
(-1575 4175);
DISPLAY 0.680851 (-1575 4175);
DISPLAY INVISIBLE (-1575 4175);
FORCEADD Q_RES..1
(-2525 800);
FORCEPROP 1 LAST LOCATION R1316
J 0
(-2775 800);
DISPLAY 0.510638 (-2775 800);
FORCEPROP 0 LAST $SEC 1
J 0
(-2375 950);
DISPLAY 0.680851 (-2375 950);
PAINT MONO (-2375 950);
DISPLAY INVISIBLE (-2375 950);
FORCEPROP 0 LAST CDS_SEC 1
J 0
(-2375 950);
DISPLAY 0.680851 (-2375 950);
DISPLAY INVISIBLE (-2375 950);
FORCEPROP 1 LASTPIN (-2625 800) $PN 1
J 0
(-2613 812);
DISPLAY 0.787234 (-2613 812);
PAINT MONO (-2613 812);
FORCEPROP 1 LASTPIN (-2425 800) $PN 2
J 0
(-2463 812);
DISPLAY 0.787234 (-2463 812);
PAINT MONO (-2463 812);
FORCEPROP 1 LAST VALUE 2.2K
J 2
(-2250 800);
DISPLAY 0.638298 (-2250 800);
FORCEPROP 1 LAST MATERIAL CHIP
J 0
(-2150 800);
DISPLAY 0.638298 (-2150 800);
FORCEPROP 1 LAST TOLERANCE 5%
J 0
(-2250 800);
DISPLAY 0.638298 (-2250 800);
FORCEPROP 1 LAST PACK_TYPE 0402LF
J 0
(-2675 925);
DISPLAY 0.510638 (-2675 925);
FORCEPROP 1 LAST WATTAGE 1/16W
J 2
(-2375 925);
DISPLAY 0.510638 (-2375 925);
FORCEPROP 2 LAST CDS_LIB pure_quanta
J 0
(-2525 800);
DISPLAY INVISIBLE (-2525 800);
FORCEPROP 1 LAST PATH I83
J 0
(-2575 950);
DISPLAY 0.978723 (-2575 950);
PAINT WHITE (-2575 950);
DISPLAY INVISIBLE (-2575 950);
FORCEPROP 1 LAST PART_NUMBER CS22202JB07
J 0
(-2675 875);
DISPLAY 0.510638 (-2675 875);
DISPLAY INVISIBLE (-2675 875);
FORCEADD Q_RES..1
(-2525 750);
FORCEPROP 1 LAST LOCATION R1341
J 0
(-2775 750);
DISPLAY 0.510638 (-2775 750);
FORCEPROP 0 LAST $SEC 1
J 0
(-2150 800);
DISPLAY 0.680851 (-2150 800);
PAINT MONO (-2150 800);
DISPLAY INVISIBLE (-2150 800);
FORCEPROP 0 LAST CDS_SEC 1
J 0
(-2150 800);
DISPLAY 0.680851 (-2150 800);
DISPLAY INVISIBLE (-2150 800);
FORCEPROP 1 LASTPIN (-2625 750) $PN 1
J 0
(-2613 762);
DISPLAY 0.787234 (-2613 762);
PAINT MONO (-2613 762);
FORCEPROP 1 LASTPIN (-2425 750) $PN 2
J 0
(-2463 762);
DISPLAY 0.787234 (-2463 762);
PAINT MONO (-2463 762);
FORCEPROP 1 LAST TOLERANCE 5%
J 0
(-2250 750);
DISPLAY 0.638298 (-2250 750);
FORCEPROP 1 LAST MATERIAL CHIP
J 0
(-2150 750);
DISPLAY 0.638298 (-2150 750);
FORCEPROP 1 LAST VALUE 2.2K
J 2
(-2250 750);
DISPLAY 0.638298 (-2250 750);
FORCEPROP 2 LAST CDS_LIB pure_quanta
J 0
(-2525 750);
DISPLAY INVISIBLE (-2525 750);
FORCEPROP 1 LAST PACK_TYPE 0402LF
J 0
(-2625 850);
DISPLAY 0.510638 (-2625 850);
DISPLAY INVISIBLE (-2625 850);
FORCEPROP 1 LAST WATTAGE 1/16W
J 2
(-2325 850);
DISPLAY 0.510638 (-2325 850);
DISPLAY INVISIBLE (-2325 850);
FORCEPROP 1 LAST PATH I84
J 0
(-2575 900);
DISPLAY 0.978723 (-2575 900);
PAINT WHITE (-2575 900);
DISPLAY INVISIBLE (-2575 900);
FORCEPROP 1 LAST PART_NUMBER CS22202JB07
J 0
(-2625 800);
DISPLAY 0.510638 (-2625 800);
DISPLAY INVISIBLE (-2625 800);
FORCEADD OFFPAGE..2
(-1200 800);
FORCEPROP 2 LAST $XR1 259 
J 0
(-891 800);
DISPLAY 0.638298 (-891 800);
PAINT MONO (-891 800);
FORCEPROP 2 LAST $XR0 253 
J 0
(-1011 800);
DISPLAY 0.638298 (-1011 800);
PAINT MONO (-1011 800);
FORCEPROP 2 LAST CDS_LIB standard
J 0
(-1200 800);
DISPLAY INVISIBLE (-1200 800);
FORCEPROP 1 LAST OFFPAGE TRUE
J 0
(-875 675);
DISPLAY 0.872340 (-875 675);
PAINT GREEN (-875 675);
DISPLAY INVISIBLE (-875 675);
FORCEPROP 1 LAST COMMENT_BODY TRUE
J 0
(-1245 705);
DISPLAY 0.872340 (-1245 705);
PAINT GREEN (-1245 705);
DISPLAY INVISIBLE (-1245 705);
FORCEPROP 2 LAST PATH I85
J 0
(-1025 875);
DISPLAY 0.680851 (-1025 875);
DISPLAY INVISIBLE (-1025 875);
FORCEADD OFFPAGE..2
(-1200 750);
FORCEPROP 2 LAST $XR1 259 
J 0
(-891 750);
DISPLAY 0.638298 (-891 750);
PAINT MONO (-891 750);
FORCEPROP 2 LAST $XR0 253 
J 0
(-1011 750);
DISPLAY 0.638298 (-1011 750);
PAINT MONO (-1011 750);
FORCEPROP 2 LAST CDS_LIB standard
J 0
(-1200 750);
DISPLAY INVISIBLE (-1200 750);
FORCEPROP 1 LAST OFFPAGE TRUE
J 0
(-875 625);
DISPLAY 0.872340 (-875 625);
PAINT GREEN (-875 625);
DISPLAY INVISIBLE (-875 625);
FORCEPROP 1 LAST COMMENT_BODY TRUE
J 0
(-1245 655);
DISPLAY 0.872340 (-1245 655);
PAINT GREEN (-1245 655);
DISPLAY INVISIBLE (-1245 655);
FORCEPROP 2 LAST PATH I86
J 0
(-1025 825);
DISPLAY 0.680851 (-1025 825);
DISPLAY INVISIBLE (-1025 825);
FORCEADD UNIVERSAL_POWER..1
(-6575 3225);
FORCEPROP 3 LASTPIN (-6575 3175) SIG_NAME P3V3_AUX\g
J 0
(-6565 3185);
DISPLAY 0.659574 (-6565 3185);
PAINT MONO (-6565 3185);
DISPLAY INVISIBLE (-6565 3185);
FORCEPROP 1 LAST HDL_POWER P3V3_AUX
J 1
(-6575 3275);
DISPLAY 0.872340 (-6575 3275);
PAINT GREEN (-6575 3275);
FORCEPROP 2 LAST CDS_LIB pure_quanta_power
J 0
(-6575 3225);
PAINT MONO (-6575 3225);
DISPLAY INVISIBLE (-6575 3225);
FORCEPROP 1 LAST PATH I9
J 0
(-6525 3250);
DISPLAY 0.872340 (-6525 3250);
PAINT AQUA (-6525 3250);
DISPLAY INVISIBLE (-6525 3250);
FORCEADD DNS..2
(-6950 4725);
PAINT RED (-6950 4725);
FORCEPROP 2 LAST CDS_LIB mstr_misc
J 0
(-6950 4725);
DISPLAY INVISIBLE (-6950 4725);
FORCEPROP 1 LAST COMMENT_BODY TRUE
J 0
(-6950 4725);
DISPLAY INVISIBLE (-6950 4725);
FORCEADD DNS..2
(-6020 2820);
PAINT RED (-6020 2820);
FORCEPROP 2 LAST CDS_LIB mstr_misc
J 0
(-6020 2820);
PAINT MONO (-6020 2820);
DISPLAY INVISIBLE (-6020 2820);
FORCEPROP 1 LAST COMMENT_BODY TRUE
J 0
(-6020 2820);
DISPLAY INVISIBLE (-6020 2820);
FORCEADD DNS..2
(-6295 2820);
PAINT RED (-6295 2820);
FORCEPROP 2 LAST CDS_LIB mstr_misc
J 0
(-6295 2820);
PAINT MONO (-6295 2820);
DISPLAY INVISIBLE (-6295 2820);
FORCEPROP 1 LAST COMMENT_BODY TRUE
J 0
(-6295 2820);
DISPLAY INVISIBLE (-6295 2820);
FORCEADD DNS..2
(-6570 2820);
PAINT RED (-6570 2820);
FORCEPROP 2 LAST CDS_LIB mstr_misc
J 0
(-6570 2820);
PAINT MONO (-6570 2820);
DISPLAY INVISIBLE (-6570 2820);
FORCEPROP 1 LAST COMMENT_BODY TRUE
J 0
(-6570 2820);
DISPLAY INVISIBLE (-6570 2820);
FORCEADD QUANTA_TITLE_BLOCK_C..1
(0 0);
FORCEPROP 0 LAST CDS_CON_LAST_MODIFIED Thu Sep 14 16:12:35 2023
J 0
(-1885 15);
DISPLAY INVISIBLE (-1885 15);
FORCEPROP 1 LAST CUSTOM_TXT_CDS <CON_LAST_MODIFIED>
J 0
(-1885 15);
DISPLAY 0.978723 (-1885 15);
FORCEPROP 2 LAST CUSTOM_TXT_CDS <XR_PAGE_TITLE>
J 0
(-7890 5250);
DISPLAY 0.638298 (-7890 5250);
PAINT PINK (-7890 5250);
DISPLAY INVISIBLE (-7890 5250);
FORCEPROP 1 LAST CUSTOM_TXT_CDS <NAME_2>
J 0
(-3175 50);
FORCEPROP 1 LAST CUSTOM_TXT_CDS <NAME_1>
J 0
(-3175 175);
FORCEPROP 1 LAST CUSTOM_TXT_CDS <Q_NUMBER>
J 0
(-1403 103);
DISPLAY 1.212766 (-1403 103);
FORCEPROP 1 LAST CUSTOM_TXT_CDS <Q_PROJ>
J 0
(-2382 102);
DISPLAY 1.212766 (-2382 102);
FORCEPROP 1 LAST CUSTOM_TXT_CDS <Q_REV>
J 0
(-184 103);
DISPLAY 1.212766 (-184 103);
FORCEPROP 1 LAST CUSTOM_TXT_CDS <CON_PAGE_NUM> OF <CON_TOTAL_PAGES>
J 0
(-446 18);
DISPLAY 0.978723 (-446 18);
FORCEPROP 1 LAST Q_TITLE SMBUS - PCIE2  SMBUS
J 0
(-9366 26);
DISPLAY 2.446809 (-9366 26);
PAINT GREEN (-9366 26);
FORCEPROP 2 LAST CDS_LIB pure_quanta
J 0
(0 0);
DISPLAY INVISIBLE (0 0);
FORCEPROP 1 LAST CDS_LMAN_SYM_OUTLINE -9475,6775,100,-125
J 0
(0 0);
DISPLAY 0.468085 (0 0);
PAINT GREEN (0 0);
DISPLAY INVISIBLE (0 0);
FORCEPROP 2 LAST PAGE_BORDER TRUE
J 0
(-7890 5250);
DISPLAY 0.638298 (-7890 5250);
PAINT PINK (-7890 5250);
DISPLAY INVISIBLE (-7890 5250);
FORCEPROP 2 LAST CDS_XR_PAGE_TITLE CR-253 : @T6G_MB_LIB.T6G(SCH_1):PAGE253
J 0
(-7890 5250);
DISPLAY 0.638298 (-7890 5250);
PAINT PINK (-7890 5250);
DISPLAY INVISIBLE (-7890 5250);
FORCEPROP 1 LAST Q_DEPT BU9
J 1
(-3763 49);
DISPLAY 1.957447 (-3763 49);
PAINT GREEN (-3763 49);
DISPLAY INVISIBLE (-3763 49);
FORCEPROP 1 LAST COMMENT_BODY TRUE
J 0
(12 -13);
DISPLAY 0.978723 (12 -13);
PAINT GREEN (12 -13);
DISPLAY INVISIBLE (12 -13);
FORCEADD DNS..2
(-2525 1275);
PAINT RED (-2525 1275);
FORCEPROP 2 LAST CDS_LIB mstr_misc
J 0
(-2525 1275);
DISPLAY INVISIBLE (-2525 1275);
FORCEPROP 1 LAST COMMENT_BODY TRUE
J 0
(-2525 1275);
DISPLAY INVISIBLE (-2525 1275);
FORCEADD DNS..2
(-2525 1325);
PAINT RED (-2525 1325);
FORCEPROP 2 LAST CDS_LIB mstr_misc
J 0
(-2525 1325);
DISPLAY INVISIBLE (-2525 1325);
FORCEPROP 1 LAST COMMENT_BODY TRUE
J 0
(-2525 1325);
DISPLAY INVISIBLE (-2525 1325);
WIRE 16 -1 (-6575 2025)(-6575 2100);
WIRE 16 -1 (-6950 4975)(-6950 4850);
WIRE 16 -1 (-6300 2025)(-6300 2100);
WIRE 16 -1 (-5150 4925)(-5150 4850);
WIRE 16 -1 (-3825 3850)(-3825 3725);
WIRE 16 -1 (-3825 3850)(-3925 3850);
WIRE 16 -1 (-6025 2025)(-6025 2100);
WIRE 16 -1 (-1225 1275)(-2450 1275);
FORCEPROP 0 LAST CDS_PHYS_NET_NAME SMB_VR_SENSOR_3V3AUX_SDA
J 0
(-2235 1323);
PAINT MONO (-2235 1323);
DISPLAY INVISIBLE (-2235 1323);
FORCEPROP 2 LAST SIG_NAME SMB_VR_SENSOR_3V3AUX_SDA
J 0
(-1935 1285);
DISPLAY 0.510638 (-1935 1285);
PAINT WHITE (-1935 1285);
WIRE 16 -1 (-1225 1325)(-2450 1325);
FORCEPROP 0 LAST CDS_PHYS_NET_NAME SMB_VR_SENSOR_3V3AUX_SCL
J 0
(-2235 1373);
PAINT MONO (-2235 1373);
DISPLAY INVISIBLE (-2235 1373);
FORCEPROP 2 LAST SIG_NAME SMB_VR_SENSOR_3V3AUX_SCL
J 0
(-1935 1335);
DISPLAY 0.510638 (-1935 1335);
PAINT WHITE (-1935 1335);
WIRE 16 -1 (-2650 1275)(-3000 1275);
WIRE 16 -1 (-3000 1325)(-3000 1275);
WIRE 16 -1 (-3000 1275)(-3000 800);
WIRE 16 -1 (-3000 800)(-2625 800);
WIRE 16 -1 (-3000 800)(-3000 750);
WIRE 16 -1 (-2650 1325)(-3000 1325);
WIRE 16 -1 (-3000 1525)(-3000 1325);
WIRE 16 -1 (-3000 1525)(-3000 1575);
WIRE 16 -1 (-3000 1525)(-2650 1525);
WIRE 16 -1 (-3000 750)(-2625 750);
WIRE 16 -1 (-3000 1575)(-2650 1575);
WIRE 16 -1 (-3000 1825)(-3000 1575);
WIRE 16 -1 (-3000 1825)(-2650 1825);
WIRE 16 -1 (-3000 1875)(-3000 1825);
WIRE 16 -1 (-3000 2125)(-3000 1875);
WIRE 16 -1 (-3000 1875)(-2650 1875);
WIRE 16 -1 (-3000 2125)(-2675 2125);
WIRE 16 -1 (-3000 2175)(-3000 2125);
WIRE 16 -1 (-3000 2175)(-2675 2175);
WIRE 16 -1 (-3000 2400)(-3000 2175);
WIRE 16 -1 (-3000 2400)(-2675 2400);
WIRE 16 -1 (-3000 2450)(-3000 2400);
WIRE 16 -1 (-3000 2775)(-3000 2450);
WIRE 16 -1 (-3000 2450)(-2675 2450);
WIRE 16 -1 (-3000 2775)(-2675 2775);
WIRE 16 -1 (-3000 2825)(-3000 2775);
WIRE 16 -1 (-3000 2825)(-2675 2825);
WIRE 16 -1 (-3000 2975)(-3000 2825);
WIRE 16 -1 (-2425 800)(-1250 800);
FORCEPROP 2 LAST SIG_NAME SMB_ADC_SCL_R
J 0
(-1935 810);
DISPLAY 0.680851 (-1935 810);
WIRE 16 -1 (-2425 750)(-1250 750);
FORCEPROP 2 LAST SIG_NAME SMB_ADC_SDA_R
J 0
(-1935 760);
DISPLAY 0.680851 (-1935 760);
WIRE 16 -1 (-1225 2775)(-2475 2775);
FORCEPROP 0 LAST CDS_PHYS_NET_NAME SMB_VR_3V3AUX_SDA
J 0
(-2260 2823);
PAINT MONO (-2260 2823);
DISPLAY INVISIBLE (-2260 2823);
FORCEPROP 2 LAST SIG_NAME SMB_VR_3V3AUX_SDA
J 0
(-1960 2785);
DISPLAY 0.510638 (-1960 2785);
PAINT WHITE (-1960 2785);
WIRE 16 -1 (-1225 2825)(-2475 2825);
FORCEPROP 0 LAST CDS_PHYS_NET_NAME SMB_VR_3V3AUX_SCL
J 0
(-2260 2873);
PAINT MONO (-2260 2873);
DISPLAY INVISIBLE (-2260 2873);
FORCEPROP 2 LAST SIG_NAME SMB_VR_3V3AUX_SCL
J 0
(-1960 2835);
DISPLAY 0.510638 (-1960 2835);
PAINT WHITE (-1960 2835);
WIRE 16 -1 (-6025 2425)(-4950 2425);
FORCEPROP 2 LAST SIG_NAME PCA9548_PCIE0_ADDR0
J 0
(-5835 2435);
DISPLAY 0.808511 (-5835 2435);
PAINT WHITE (-5835 2435);
WIRE 16 -1 (-6025 2750)(-6025 2425);
WIRE 16 -1 (-6025 2425)(-6025 2300);
WIRE 16 -1 (-6300 2500)(-4950 2500);
FORCEPROP 2 LAST SIG_NAME PCA9548_PCIE0_ADDR1
J 0
(-5835 2510);
DISPLAY 0.808511 (-5835 2510);
PAINT WHITE (-5835 2510);
WIRE 16 -1 (-6300 2750)(-6300 2500);
WIRE 16 -1 (-6300 2500)(-6300 2300);
WIRE 16 -1 (-2850 4050)(-1800 4050);
FORCEPROP 2 LAST SIG_NAME SMB_ADC_SCL_R
J 0
(-2510 4060);
DISPLAY 0.680851 (-2510 4060);
WIRE 16 -1 (-1225 2450)(-2475 2450);
FORCEPROP 0 LAST CDS_PHYS_NET_NAME SMB_LM75_0_3V3AUX_SCL
J 0
(-2260 2498);
PAINT MONO (-2260 2498);
DISPLAY INVISIBLE (-2260 2498);
FORCEPROP 2 LAST SIG_NAME SMB_LM75_0_3V3AUX_SCL
J 0
(-1960 2460);
DISPLAY 0.510638 (-1960 2460);
PAINT WHITE (-1960 2460);
WIRE 16 -1 (-1225 2175)(-2475 2175);
FORCEPROP 0 LAST CDS_PHYS_NET_NAME SMB_LM75_1_3V3AUX_SCL
J 0
(-2260 2223);
PAINT MONO (-2260 2223);
DISPLAY INVISIBLE (-2260 2223);
FORCEPROP 2 LAST SIG_NAME SMB_LM75_1_3V3AUX_SCL
J 0
(-1960 2185);
DISPLAY 0.510638 (-1960 2185);
PAINT WHITE (-1960 2185);
WIRE 16 -1 (-2450 1825)(-1200 1825);
FORCEPROP 0 LAST CDS_PHYS_NET_NAME SMB_LM75_2_3V3AUX_SDA
J 0
(-2410 1873);
PAINT MONO (-2410 1873);
DISPLAY INVISIBLE (-2410 1873);
FORCEPROP 2 LAST SIG_NAME SMB_LM75_2_3V3AUX_SDA
J 0
(-1935 1835);
DISPLAY 0.510638 (-1935 1835);
PAINT WHITE (-1935 1835);
WIRE 16 -1 (-6300 2950)(-6300 3100);
WIRE 16 -1 (-6300 3100)(-6025 3100);
WIRE 16 -1 (-6575 3100)(-6300 3100);
WIRE 16 -1 (-6575 2950)(-6575 3100);
WIRE 16 -1 (-6575 3100)(-6575 3175);
WIRE 16 -1 (-6025 2950)(-6025 3100);
WIRE 16 -1 (-5150 5125)(-5150 5225);
WIRE 16 -1 (-5150 5225)(-4775 5225);
WIRE 16 -1 (-5150 5300)(-5150 5225);
WIRE 16 -1 (-4775 5225)(-4775 4700);
WIRE 16 -1 (-4775 4700)(-4625 4700);
WIRE 16 -1 (-1225 2400)(-2475 2400);
FORCEPROP 0 LAST CDS_PHYS_NET_NAME SMB_LM75_0_3V3AUX_SDA
J 0
(-2260 2448);
PAINT MONO (-2260 2448);
DISPLAY INVISIBLE (-2260 2448);
FORCEPROP 2 LAST SIG_NAME SMB_LM75_0_3V3AUX_SDA
J 0
(-1960 2410);
DISPLAY 0.510638 (-1960 2410);
PAINT WHITE (-1960 2410);
WIRE 16 -1 (-1225 2125)(-2475 2125);
FORCEPROP 0 LAST CDS_PHYS_NET_NAME SMB_LM75_1_3V3AUX_SDA
J 0
(-2260 2173);
PAINT MONO (-2260 2173);
DISPLAY INVISIBLE (-2260 2173);
FORCEPROP 2 LAST SIG_NAME SMB_LM75_1_3V3AUX_SDA
J 0
(-1960 2135);
DISPLAY 0.510638 (-1960 2135);
PAINT WHITE (-1960 2135);
WIRE 16 -1 (-1200 1575)(-2450 1575);
FORCEPROP 0 LAST CDS_PHYS_NET_NAME SMB_LM75_3_3V3AUX_SCL
J 0
(-2235 1623);
PAINT MONO (-2235 1623);
DISPLAY INVISIBLE (-2235 1623);
FORCEPROP 2 LAST SIG_NAME SMB_LM75_3_3V3AUX_SCL
J 0
(-1935 1585);
DISPLAY 0.510638 (-1935 1585);
PAINT WHITE (-1935 1585);
WIRE 16 -1 (-2450 1875)(-1200 1875);
FORCEPROP 0 LAST CDS_PHYS_NET_NAME SMB_LM75_2_3V3AUX_SCL
J 0
(-2410 1923);
PAINT MONO (-2410 1923);
DISPLAY INVISIBLE (-2410 1923);
FORCEPROP 2 LAST SIG_NAME SMB_LM75_2_3V3AUX_SCL
J 0
(-1935 1885);
DISPLAY 0.510638 (-1935 1885);
PAINT WHITE (-1935 1885);
WIRE 16 -1 (-2725 4500)(-1825 4500);
FORCEPROP 0 LAST CDS_PHYS_NET_NAME SMB_VR_SENSOR_3V3AUX_SCL
J 0
(-2685 4548);
PAINT MONO (-2685 4548);
DISPLAY INVISIBLE (-2685 4548);
FORCEPROP 2 LAST SIG_NAME SMB_VR_SENSOR_3V3AUX_SCL
J 0
(-2510 4510);
DISPLAY 0.510638 (-2510 4510);
PAINT WHITE (-2510 4510);
WIRE 16 -1 (-3925 4100)(-3050 4100);
FORCEPROP 2 LAST SIG_NAME SMB_ADC_SDA
J 0
(-3810 4110);
DISPLAY 0.680851 (-3810 4110);
FORCEPROP 2 LASTPROP $XRERR UNIQUE?
J 0
(-4050 4110);
DISPLAY 0.638298 (-4050 4110);
PAINT MONO (-4050 4110);
DISPLAY INVISIBLE (-4050 4110);
WIRE 16 -1 (-3925 4050)(-3050 4050);
FORCEPROP 2 LAST SIG_NAME SMB_ADC_SCL
J 0
(-3810 4060);
DISPLAY 0.680851 (-3810 4060);
FORCEPROP 2 LASTPROP $XRERR UNIQUE?
J 0
(-4050 4060);
DISPLAY 0.638298 (-4050 4060);
PAINT MONO (-4050 4060);
DISPLAY INVISIBLE (-4050 4060);
WIRE 16 -1 (-3925 4150)(-3050 4150);
FORCEPROP 2 LAST SIG_NAME SMB_P12V_HSC_SCL_R
J 0
(-3810 4160);
DISPLAY 0.553191 (-3810 4160);
FORCEPROP 2 LASTPROP $XRERR UNIQUE?
J 0
(-4050 4160);
DISPLAY 0.638298 (-4050 4160);
PAINT MONO (-4050 4160);
DISPLAY INVISIBLE (-4050 4160);
WIRE 16 -1 (-3925 4200)(-3050 4200);
FORCEPROP 2 LAST SIG_NAME SMB_P12V_HSC_SDA_R
J 0
(-3810 4210);
DISPLAY 0.553191 (-3810 4210);
FORCEPROP 2 LASTPROP $XRERR UNIQUE?
J 0
(-4050 4210);
DISPLAY 0.638298 (-4050 4210);
PAINT MONO (-4050 4210);
DISPLAY INVISIBLE (-4050 4210);
WIRE 16 -1 (-3925 4250)(-3050 4250);
FORCEPROP 0 LAST CDS_PHYS_NET_NAME SMB_LM75_3_3V3AUX_SCL_R
J 0
(-3885 4298);
PAINT MONO (-3885 4298);
DISPLAY INVISIBLE (-3885 4298);
FORCEPROP 2 LAST SIG_NAME SMB_LM75_3_3V3AUX_SCL_R
J 0
(-3810 4260);
DISPLAY 0.510638 (-3810 4260);
PAINT WHITE (-3810 4260);
FORCEPROP 2 LASTPROP $XRERR UNIQUE?
J 0
(-4050 4260);
DISPLAY 0.638298 (-4050 4260);
PAINT MONO (-4050 4260);
DISPLAY INVISIBLE (-4050 4260);
WIRE 16 -1 (-1800 4150)(-2850 4150);
FORCEPROP 2 LAST SIG_NAME SMB_P12V_HSC_SCL
J 0
(-2510 4160);
DISPLAY 0.553191 (-2510 4160);
WIRE 16 -1 (-3925 4300)(-3050 4300);
FORCEPROP 0 LAST CDS_PHYS_NET_NAME SMB_LM75_3_3V3AUX_SDA_R
J 0
(-3885 4348);
PAINT MONO (-3885 4348);
DISPLAY INVISIBLE (-3885 4348);
FORCEPROP 2 LAST SIG_NAME SMB_LM75_3_3V3AUX_SDA_R
J 0
(-3810 4310);
DISPLAY 0.510638 (-3810 4310);
PAINT WHITE (-3810 4310);
FORCEPROP 2 LASTPROP $XRERR UNIQUE?
J 0
(-4050 4310);
DISPLAY 0.638298 (-4050 4310);
PAINT MONO (-4050 4310);
DISPLAY INVISIBLE (-4050 4310);
WIRE 16 -1 (-2850 4100)(-1800 4100);
FORCEPROP 2 LAST SIG_NAME SMB_ADC_SDA_R
J 0
(-2510 4110);
DISPLAY 0.680851 (-2510 4110);
WIRE 16 -1 (-1800 4200)(-2850 4200);
FORCEPROP 2 LAST SIG_NAME SMB_P12V_HSC_SDA
J 0
(-2510 4210);
DISPLAY 0.553191 (-2510 4210);
WIRE 16 -1 (-5500 4000)(-4625 4000);
FORCEPROP 0 LAST CDS_PHYS_NET_NAME SMB_LM75_2_3V3AUX_SDA_R
J 0
(-5460 4048);
PAINT MONO (-5460 4048);
DISPLAY INVISIBLE (-5460 4048);
FORCEPROP 2 LAST SIG_NAME SMB_LM75_2_3V3AUX_SDA_R
J 0
(-5235 4010);
DISPLAY 0.510638 (-5235 4010);
PAINT WHITE (-5235 4010);
FORCEPROP 2 LASTPROP $XRERR UNIQUE?
J 0
(-5475 4010);
DISPLAY 0.638298 (-5475 4010);
PAINT MONO (-5475 4010);
DISPLAY INVISIBLE (-5475 4010);
WIRE 16 -1 (-5500 3950)(-4625 3950);
FORCEPROP 0 LAST CDS_PHYS_NET_NAME SMB_LM75_2_3V3AUX_SCL_R
J 0
(-5460 3998);
PAINT MONO (-5460 3998);
DISPLAY INVISIBLE (-5460 3998);
FORCEPROP 2 LAST SIG_NAME SMB_LM75_2_3V3AUX_SCL_R
J 0
(-5235 3960);
DISPLAY 0.510638 (-5235 3960);
PAINT WHITE (-5235 3960);
FORCEPROP 2 LASTPROP $XRERR UNIQUE?
J 0
(-5475 3960);
DISPLAY 0.638298 (-5475 3960);
PAINT MONO (-5475 3960);
DISPLAY INVISIBLE (-5475 3960);
WIRE 16 -1 (-4625 4200)(-5500 4200);
FORCEPROP 0 LAST CDS_PHYS_NET_NAME SMB_LM75_0_3V3AUX_SDA_R
J 0
(-5460 4248);
PAINT MONO (-5460 4248);
DISPLAY INVISIBLE (-5460 4248);
FORCEPROP 2 LAST SIG_NAME SMB_LM75_0_3V3AUX_SDA_R
J 0
(-5235 4210);
DISPLAY 0.510638 (-5235 4210);
PAINT WHITE (-5235 4210);
FORCEPROP 2 LASTPROP $XRERR UNIQUE?
J 0
(-5475 4210);
DISPLAY 0.638298 (-5475 4210);
PAINT MONO (-5475 4210);
DISPLAY INVISIBLE (-5475 4210);
WIRE 16 -1 (-4625 4150)(-5500 4150);
FORCEPROP 0 LAST CDS_PHYS_NET_NAME SMB_LM75_0_3V3AUX_SCL_R
J 0
(-5460 4198);
PAINT MONO (-5460 4198);
DISPLAY INVISIBLE (-5460 4198);
FORCEPROP 2 LAST SIG_NAME SMB_LM75_0_3V3AUX_SCL_R
J 0
(-5235 4160);
DISPLAY 0.510638 (-5235 4160);
PAINT WHITE (-5235 4160);
FORCEPROP 2 LASTPROP $XRERR UNIQUE?
J 0
(-5475 4160);
DISPLAY 0.638298 (-5475 4160);
PAINT MONO (-5475 4160);
DISPLAY INVISIBLE (-5475 4160);
WIRE 16 -1 (-5500 4250)(-4625 4250);
FORCEPROP 0 LAST CDS_PHYS_NET_NAME SMB_VR_3V3AUX_SCL_R6
J 0
(-5460 4298);
PAINT MONO (-5460 4298);
DISPLAY INVISIBLE (-5460 4298);
FORCEPROP 2 LAST SIG_NAME SMB_VR_3V3AUX_SCL_R6
J 0
(-5235 4260);
DISPLAY 0.510638 (-5235 4260);
PAINT WHITE (-5235 4260);
FORCEPROP 2 LASTPROP $XRERR UNIQUE?
J 0
(-5475 4260);
DISPLAY 0.638298 (-5475 4260);
PAINT MONO (-5475 4260);
DISPLAY INVISIBLE (-5475 4260);
WIRE 16 -1 (-5500 4300)(-4625 4300);
FORCEPROP 0 LAST CDS_PHYS_NET_NAME SMB_VR_3V3AUX_SDA_R6
J 0
(-5460 4348);
PAINT MONO (-5460 4348);
DISPLAY INVISIBLE (-5460 4348);
FORCEPROP 2 LAST SIG_NAME SMB_VR_3V3AUX_SDA_R6
J 0
(-5235 4310);
DISPLAY 0.510638 (-5235 4310);
PAINT WHITE (-5235 4310);
FORCEPROP 2 LASTPROP $XRERR UNIQUE?
J 0
(-5475 4310);
DISPLAY 0.638298 (-5475 4310);
PAINT MONO (-5475 4310);
DISPLAY INVISIBLE (-5475 4310);
WIRE 16 -1 (-6750 4300)(-5700 4300);
FORCEPROP 0 LAST CDS_PHYS_NET_NAME SMB_VR_3V3AUX_SDA
J 0
(-6710 4348);
PAINT MONO (-6710 4348);
DISPLAY INVISIBLE (-6710 4348);
FORCEPROP 2 LAST SIG_NAME SMB_VR_3V3AUX_SDA
J 0
(-6410 4310);
DISPLAY 0.510638 (-6410 4310);
PAINT WHITE (-6410 4310);
WIRE 16 -1 (-6750 4250)(-5700 4250);
FORCEPROP 0 LAST CDS_PHYS_NET_NAME SMB_VR_3V3AUX_SCL
J 0
(-6685 4298);
PAINT MONO (-6685 4298);
DISPLAY INVISIBLE (-6685 4298);
FORCEPROP 2 LAST SIG_NAME SMB_VR_3V3AUX_SCL
J 0
(-6410 4260);
DISPLAY 0.510638 (-6410 4260);
PAINT WHITE (-6410 4260);
WIRE 16 -1 (-6750 4200)(-5700 4200);
FORCEPROP 0 LAST CDS_PHYS_NET_NAME SMB_LM75_0_3V3AUX_SDA
J 0
(-6710 4248);
PAINT MONO (-6710 4248);
DISPLAY INVISIBLE (-6710 4248);
FORCEPROP 2 LAST SIG_NAME SMB_LM75_0_3V3AUX_SDA
J 0
(-6410 4210);
DISPLAY 0.510638 (-6410 4210);
PAINT WHITE (-6410 4210);
WIRE 16 -1 (-6750 4150)(-5700 4150);
FORCEPROP 0 LAST CDS_PHYS_NET_NAME SMB_LM75_0_3V3AUX_SCL
J 0
(-6710 4198);
PAINT MONO (-6710 4198);
DISPLAY INVISIBLE (-6710 4198);
FORCEPROP 2 LAST SIG_NAME SMB_LM75_0_3V3AUX_SCL
J 0
(-6410 4160);
DISPLAY 0.510638 (-6410 4160);
PAINT WHITE (-6410 4160);
WIRE 16 -1 (-5700 3950)(-6750 3950);
FORCEPROP 0 LAST CDS_PHYS_NET_NAME SMB_LM75_2_3V3AUX_SCL
J 0
(-7910 3998);
PAINT MONO (-7910 3998);
DISPLAY INVISIBLE (-7910 3998);
FORCEPROP 2 LAST SIG_NAME SMB_LM75_2_3V3AUX_SCL
J 0
(-6410 3960);
DISPLAY 0.510638 (-6410 3960);
PAINT WHITE (-6410 3960);
WIRE 16 -1 (-5700 4000)(-6750 4000);
FORCEPROP 0 LAST CDS_PHYS_NET_NAME SMB_LM75_2_3V3AUX_SDA
J 0
(-7910 4048);
PAINT MONO (-7910 4048);
DISPLAY INVISIBLE (-7910 4048);
FORCEPROP 2 LAST SIG_NAME SMB_LM75_2_3V3AUX_SDA
J 0
(-6410 4010);
DISPLAY 0.510638 (-6410 4010);
PAINT WHITE (-6410 4010);
WIRE 16 -1 (-5700 4050)(-6750 4050);
FORCEPROP 0 LAST CDS_PHYS_NET_NAME SMB_LM75_1_3V3AUX_SCL
J 0
(-7910 4098);
PAINT MONO (-7910 4098);
DISPLAY INVISIBLE (-7910 4098);
FORCEPROP 2 LAST SIG_NAME SMB_LM75_1_3V3AUX_SCL
J 0
(-6410 4060);
DISPLAY 0.510638 (-6410 4060);
PAINT WHITE (-6410 4060);
WIRE 16 -1 (-5700 4100)(-6750 4100);
FORCEPROP 0 LAST CDS_PHYS_NET_NAME SMB_LM75_1_3V3AUX_SDA
J 0
(-7910 4148);
PAINT MONO (-7910 4148);
DISPLAY INVISIBLE (-7910 4148);
FORCEPROP 2 LAST SIG_NAME SMB_LM75_1_3V3AUX_SDA
J 0
(-6410 4110);
DISPLAY 0.510638 (-6410 4110);
PAINT WHITE (-6410 4110);
WIRE 16 -1 (-5500 4100)(-4625 4100);
FORCEPROP 0 LAST CDS_PHYS_NET_NAME SMB_LM75_1_3V3AUX_SDA_R
J 0
(-5460 4148);
PAINT MONO (-5460 4148);
DISPLAY INVISIBLE (-5460 4148);
FORCEPROP 2 LAST SIG_NAME SMB_LM75_1_3V3AUX_SDA_R
J 0
(-5235 4110);
DISPLAY 0.510638 (-5235 4110);
PAINT WHITE (-5235 4110);
FORCEPROP 2 LASTPROP $XRERR UNIQUE?
J 0
(-5475 4110);
DISPLAY 0.638298 (-5475 4110);
PAINT MONO (-5475 4110);
DISPLAY INVISIBLE (-5475 4110);
WIRE 16 -1 (-5500 4050)(-4625 4050);
FORCEPROP 0 LAST CDS_PHYS_NET_NAME SMB_LM75_1_3V3AUX_SCL_R
J 0
(-5460 4098);
PAINT MONO (-5460 4098);
DISPLAY INVISIBLE (-5460 4098);
FORCEPROP 2 LAST SIG_NAME SMB_LM75_1_3V3AUX_SCL_R
J 0
(-5235 4060);
DISPLAY 0.510638 (-5235 4060);
PAINT WHITE (-5235 4060);
FORCEPROP 2 LASTPROP $XRERR UNIQUE?
J 0
(-5475 4060);
DISPLAY 0.638298 (-5475 4060);
PAINT MONO (-5475 4060);
DISPLAY INVISIBLE (-5475 4060);
WIRE 16 -1 (-4625 4400)(-5750 4400);
FORCEPROP 0 LAST CDS_PHYS_NET_NAME PU_RST_SMB_PCIE2_N
J 0
(-5710 4448);
PAINT MONO (-5710 4448);
DISPLAY INVISIBLE (-5710 4448);
FORCEPROP 2 LAST SIG_NAME PU_RST_SMB_PCIE2_N
J 0
(-5260 4410);
DISPLAY 0.510638 (-5260 4410);
PAINT WHITE (-5260 4410);
FORCEPROP 2 LASTPROP $XRERR UNIQUE?
J 0
(-5500 4410);
DISPLAY 0.638298 (-5500 4410);
PAINT MONO (-5500 4410);
DISPLAY INVISIBLE (-5500 4410);
WIRE 16 -1 (-5300 4550)(-4625 4550);
FORCEPROP 2 LAST SIG_NAME PCA9548_PCIE0_ADDR1
J 0
(-5260 4560);
DISPLAY 0.510638 (-5260 4560);
PAINT WHITE (-5260 4560);
WIRE 16 -1 (-5300 4600)(-4625 4600);
FORCEPROP 2 LAST SIG_NAME PCA9548_PCIE0_ADDR0
J 0
(-5260 4610);
DISPLAY 0.510638 (-5260 4610);
PAINT WHITE (-5260 4610);
WIRE 16 -1 (-1200 1525)(-2450 1525);
FORCEPROP 0 LAST CDS_PHYS_NET_NAME SMB_LM75_3_3V3AUX_SDA
J 0
(-2235 1573);
PAINT MONO (-2235 1573);
DISPLAY INVISIBLE (-2235 1573);
FORCEPROP 2 LAST SIG_NAME SMB_LM75_3_3V3AUX_SDA
J 0
(-1935 1535);
DISPLAY 0.510638 (-1935 1535);
PAINT WHITE (-1935 1535);
WIRE 16 -1 (-7425 4400)(-6950 4400);
FORCEPROP 0 LAST CDS_PHYS_NET_NAME RST_SMB_SWITCH_N
J 0
(-7385 4448);
PAINT MONO (-7385 4448);
DISPLAY INVISIBLE (-7385 4448);
FORCEPROP 2 LAST SIG_NAME RST_SMB_SWITCH_N
J 0
(-7410 4410);
DISPLAY 0.510638 (-7410 4410);
PAINT WHITE (-7410 4410);
WIRE 16 -1 (-5950 4400)(-6950 4400);
WIRE 16 -1 (-6950 4650)(-6950 4400);
WIRE 16 -1 (-2725 4550)(-1825 4550);
FORCEPROP 0 LAST CDS_PHYS_NET_NAME SMB_VR_SENSOR_3V3AUX_SDA
J 0
(-2685 4598);
PAINT MONO (-2685 4598);
DISPLAY INVISIBLE (-2685 4598);
FORCEPROP 2 LAST SIG_NAME SMB_VR_SENSOR_3V3AUX_SDA
J 0
(-2510 4560);
DISPLAY 0.510638 (-2510 4560);
PAINT WHITE (-2510 4560);
WIRE 16 -1 (-3925 4550)(-2925 4550);
FORCEPROP 0 LAST CDS_PHYS_NET_NAME SMB_VR_SENSOR_3V3AUX_SDA_R
J 0
(-3885 4598);
PAINT MONO (-3885 4598);
DISPLAY INVISIBLE (-3885 4598);
FORCEPROP 2 LAST SIG_NAME SMB_VR_SENSOR_3V3AUX_SDA_R
J 0
(-3860 4560);
DISPLAY 0.510638 (-3860 4560);
PAINT WHITE (-3860 4560);
FORCEPROP 2 LASTPROP $XRERR UNIQUE?
J 0
(-4100 4560);
DISPLAY 0.638298 (-4100 4560);
PAINT MONO (-4100 4560);
DISPLAY INVISIBLE (-4100 4560);
WIRE 16 -1 (-1800 4300)(-2850 4300);
FORCEPROP 0 LAST CDS_PHYS_NET_NAME SMB_LM75_3_3V3AUX_SDA
J 0
(-4010 4348);
PAINT MONO (-4010 4348);
DISPLAY INVISIBLE (-4010 4348);
FORCEPROP 2 LAST SIG_NAME SMB_LM75_3_3V3AUX_SDA
J 0
(-2510 4310);
DISPLAY 0.510638 (-2510 4310);
PAINT WHITE (-2510 4310);
WIRE 16 -1 (-3925 4500)(-2925 4500);
FORCEPROP 0 LAST CDS_PHYS_NET_NAME SMB_VR_SENSOR_3V3AUX_SCL_R
J 0
(-3885 4548);
PAINT MONO (-3885 4548);
DISPLAY INVISIBLE (-3885 4548);
FORCEPROP 2 LAST SIG_NAME SMB_VR_SENSOR_3V3AUX_SCL_R
J 0
(-3860 4510);
DISPLAY 0.510638 (-3860 4510);
PAINT WHITE (-3860 4510);
FORCEPROP 2 LASTPROP $XRERR UNIQUE?
J 0
(-4100 4510);
DISPLAY 0.638298 (-4100 4510);
PAINT MONO (-4100 4510);
DISPLAY INVISIBLE (-4100 4510);
WIRE 16 -1 (-5300 4500)(-4625 4500);
FORCEPROP 0 LAST CDS_PHYS_NET_NAME PCA9548_PCIE0_ADDR2
J 0
(-5260 4548);
PAINT MONO (-5260 4548);
DISPLAY INVISIBLE (-5260 4548);
FORCEPROP 2 LAST SIG_NAME PCA9548_PCIE0_ADDR2
J 0
(-5260 4510);
DISPLAY 0.510638 (-5260 4510);
PAINT WHITE (-5260 4510);
WIRE 16 -1 (-1800 4250)(-2850 4250);
FORCEPROP 0 LAST CDS_PHYS_NET_NAME SMB_LM75_3_3V3AUX_SCL
J 0
(-4010 4298);
PAINT MONO (-4010 4298);
DISPLAY INVISIBLE (-4010 4298);
FORCEPROP 2 LAST SIG_NAME SMB_LM75_3_3V3AUX_SCL
J 0
(-2510 4260);
DISPLAY 0.510638 (-2510 4260);
PAINT WHITE (-2510 4260);
WIRE 16 -1 (-6575 2575)(-4950 2575);
FORCEPROP 2 LAST SIG_NAME PCA9548_PCIE0_ADDR2
J 0
(-5835 2585);
DISPLAY 0.808511 (-5835 2585);
PAINT WHITE (-5835 2585);
WIRE 16 -1 (-6575 2750)(-6575 2575);
WIRE 16 -1 (-6575 2575)(-6575 2300);
DOT 1 (-3000 800);
DOT 1 (-3000 1275);
DOT 1 (-3000 1875);
DOT 1 (-6300 3100);
DOT 1 (-6025 2425);
DOT 1 (-6575 3100);
DOT 1 (-6575 2575);
DOT 1 (-6300 2500);
DOT 1 (-3000 2825);
DOT 1 (-3000 2775);
DOT 1 (-3000 2450);
DOT 1 (-3000 2400);
DOT 1 (-3000 2175);
DOT 1 (-3000 2125);
DOT 1 (-3000 1825);
DOT 1 (-3000 1575);
DOT 1 (-3000 1525);
DOT 1 (-3000 1325);
DOT 1 (-5150 5225);
DOT 1 (-6950 4400);
FORCENOTE
PCA9548 ADDR: 0XE0 (8-BIT) / 0X70 (7-BIT)
(-7025 3500) 0;
DISPLAY LEFT (-7025 3500);
DISPLAY 1.595745 (-7025 3500);
PAINT SKYBLUE (-7025 3500);
QUIT
